FILE_TYPE = MACRO_DRAWING;
SET COLOR_WIRE YELLOW;
SET COLOR_PROP MONO;
SET COLOR_DOT WHITE;
SET COLOR_ARC YELLOW;
SET COLOR_BODY GREEN;
SET COLOR_NOTE MONO;
SET PROP_DISPLAY VALUE;
SET PAGE_NUMBER P199;
FORCEADD ADM1278..1
(-3250 2575);
FORCEPROP 2 LASTPIN (-4000 1925) $PN 29
J 2
(-4010 1935);
DISPLAY 0.617021 (-4010 1935);
PAINT ORANGE (-4010 1935);
FORCEPROP 2 LASTPIN (-4000 1875) $PN 26
J 2
(-4010 1885);
DISPLAY 0.617021 (-4010 1885);
PAINT ORANGE (-4010 1885);
FORCEPROP 1 LAST PART_NUMBER G99251-001
J 0
(-3950 1675);
DISPLAY 0.617021 (-3950 1675);
PAINT BLUE (-3950 1675);
FORCEPROP 2 LASTPIN (-4000 2025) $PN 27
J 2
(-4010 2035);
DISPLAY 0.617021 (-4010 2035);
PAINT ORANGE (-4010 2035);
FORCEPROP 2 LASTPIN (-4000 2175) $PN 25
J 2
(-4010 2185);
DISPLAY 0.617021 (-4010 2185);
PAINT ORANGE (-4010 2185);
FORCEPROP 2 LASTPIN (-4000 2225) $PN 21
J 2
(-4010 2235);
DISPLAY 0.617021 (-4010 2235);
PAINT ORANGE (-4010 2235);
FORCEPROP 2 LASTPIN (-4000 2075) $PN 28
J 2
(-4010 2085);
DISPLAY 0.617021 (-4010 2085);
PAINT ORANGE (-4010 2085);
FORCEPROP 2 LASTPIN (-4000 2275) $PN 9
J 2
(-4010 2285);
DISPLAY 0.617021 (-4010 2285);
PAINT ORANGE (-4010 2285);
FORCEPROP 2 LASTPIN (-4000 2425) $PN 18
J 2
(-4010 2435);
DISPLAY 0.617021 (-4010 2435);
PAINT ORANGE (-4010 2435);
FORCEPROP 2 LASTPIN (-4000 2375) $PN 6
J 2
(-4010 2385);
DISPLAY 0.617021 (-4010 2385);
PAINT ORANGE (-4010 2385);
FORCEPROP 2 LASTPIN (-4000 2325) $PN 12
J 2
(-4010 2335);
DISPLAY 0.617021 (-4010 2335);
PAINT ORANGE (-4010 2335);
FORCEPROP 2 LASTPIN (-4000 2525) $PN 8
J 2
(-4010 2535);
DISPLAY 0.617021 (-4010 2535);
PAINT ORANGE (-4010 2535);
FORCEPROP 2 LASTPIN (-4000 2675) $PN 15
J 2
(-4010 2685);
DISPLAY 0.617021 (-4010 2685);
PAINT ORANGE (-4010 2685);
FORCEPROP 2 LASTPIN (-4000 2725) $PN 16
J 2
(-4010 2735);
DISPLAY 0.617021 (-4010 2735);
PAINT ORANGE (-4010 2735);
FORCEPROP 2 LASTPIN (-4000 2775) $PN 17
J 2
(-4010 2785);
DISPLAY 0.617021 (-4010 2785);
PAINT ORANGE (-4010 2785);
FORCEPROP 2 LASTPIN (-4000 2575) $PN 7
J 2
(-4010 2585);
DISPLAY 0.617021 (-4010 2585);
PAINT ORANGE (-4010 2585);
FORCEPROP 2 LASTPIN (-4000 2975) $PN 3
J 2
(-4010 2985);
DISPLAY 0.617021 (-4010 2985);
PAINT ORANGE (-4010 2985);
FORCEPROP 2 LASTPIN (-4000 2875) $PN 4
J 2
(-4010 2885);
DISPLAY 0.617021 (-4010 2885);
PAINT ORANGE (-4010 2885);
FORCEPROP 2 LASTPIN (-4000 2925) $PN 1
J 2
(-4010 2935);
DISPLAY 0.617021 (-4010 2935);
PAINT ORANGE (-4010 2935);
FORCEPROP 2 LASTPIN (-4000 2825) $PN 5
J 2
(-4010 2835);
DISPLAY 0.617021 (-4010 2835);
PAINT ORANGE (-4010 2835);
FORCEPROP 2 LASTPIN (-4000 3075) $PN 32
J 2
(-4010 3085);
DISPLAY 0.617021 (-4010 3085);
PAINT ORANGE (-4010 3085);
FORCEPROP 2 LASTPIN (-4000 3275) $PN 30
J 2
(-4010 3285);
DISPLAY 0.617021 (-4010 3285);
PAINT ORANGE (-4010 3285);
FORCEPROP 2 LASTPIN (-4000 3125) $PN 31
J 2
(-4010 3135);
DISPLAY 0.617021 (-4010 3135);
PAINT ORANGE (-4010 3135);
FORCEPROP 2 LASTPIN (-4000 3175) $PN 2
J 2
(-4010 3185);
DISPLAY 0.617021 (-4010 3185);
PAINT ORANGE (-4010 3185);
FORCEPROP 1 LAST MATERIAL IC
J 0
(-3950 3475);
DISPLAY 0.617021 (-3950 3475);
PAINT SKYBLUE (-3950 3475);
FORCEPROP 1 LAST LOCATION EU1D2
J 0
(-3950 3525);
DISPLAY 0.617021 (-3950 3525);
PAINT AQUA (-3950 3525);
FORCEPROP 2 LASTPIN (-2500 2425) $PN 33
J 0
(-2490 2435);
DISPLAY 0.617021 (-2490 2435);
PAINT ORANGE (-2490 2435);
FORCEPROP 2 LASTPIN (-2500 2525) $PN 23
J 0
(-2490 2535);
DISPLAY 0.617021 (-2490 2535);
PAINT ORANGE (-2490 2535);
FORCEPROP 2 LASTPIN (-2500 2725) $PN 24
J 0
(-2490 2735);
DISPLAY 0.617021 (-2490 2735);
PAINT ORANGE (-2490 2735);
FORCEPROP 2 LASTPIN (-2500 2625) $PN 22
J 0
(-2490 2635);
DISPLAY 0.617021 (-2490 2635);
PAINT ORANGE (-2490 2635);
FORCEPROP 2 LASTPIN (-2500 2925) $PN 19
J 0
(-2490 2935);
DISPLAY 0.617021 (-2490 2935);
PAINT ORANGE (-2490 2935);
FORCEPROP 2 LASTPIN (-2500 3025) $PN 11
J 0
(-2490 3035);
DISPLAY 0.617021 (-2490 3035);
PAINT ORANGE (-2490 3035);
FORCEPROP 2 LASTPIN (-2500 2825) $PN 20
J 0
(-2490 2835);
DISPLAY 0.617021 (-2490 2835);
PAINT ORANGE (-2490 2835);
FORCEPROP 2 LASTPIN (-2500 3275) $PN 13
J 0
(-2490 3285);
DISPLAY 0.617021 (-2490 3285);
PAINT ORANGE (-2490 3285);
FORCEPROP 2 LASTPIN (-2500 3225) $PN 14
J 0
(-2490 3235);
DISPLAY 0.617021 (-2490 3235);
PAINT ORANGE (-2490 3235);
FORCEPROP 2 LASTPIN (-2500 3125) $PN 10
J 0
(-2490 3135);
DISPLAY 0.617021 (-2490 3135);
PAINT ORANGE (-2490 3135);
FORCEPROP 2 LAST CDS_LIB mstr_controller
J 0
(-3250 2575);
PAINT ORANGE (-3250 2575);
DISPLAY INVISIBLE (-3250 2575);
FORCEPROP 2 LAST CDS_LOCATION EU1D2
J 0
(-3950 3525);
DISPLAY 0.617021 (-3950 3525);
PAINT AQUA (-3950 3525);
DISPLAY INVISIBLE (-3950 3525);
FORCEPROP 2 LAST SEC 1
J 0
(-3950 3575);
DISPLAY 0.680851 (-3950 3575);
PAINT MONO (-3950 3575);
DISPLAY INVISIBLE (-3950 3575);
FORCEPROP 2 LAST SEC_TYPE SM
J 0
(-3950 3575);
DISPLAY 1.021277 (-3950 3575);
PAINT ORANGE (-3950 3575);
DISPLAY INVISIBLE (-3950 3575);
FORCEPROP 1 LAST PACK_TYPE SM
J 0
(-3950 3575);
PAINT SKYBLUE (-3950 3575);
DISPLAY INVISIBLE (-3950 3575);
FORCEPROP 0 LAST ROOM HOT_SWAP
J 0
(-3950 3625);
DISPLAY 1.021277 (-3950 3625);
PAINT ORANGE (-3950 3625);
DISPLAY INVISIBLE (-3950 3625);
FORCEPROP 1 LAST PATH I10
J 0
(-3250 3475);
PAINT GREEN (-3250 3475);
DISPLAY INVISIBLE (-3250 3475);
FORCEADD RES..2
(-5300 800);
FORCEPROP 1 LASTPIN (-5300 700) $PN 2
J 0
(-5295 710);
DISPLAY 0.617021 (-5295 710);
PAINT ORANGE (-5295 710);
FORCEPROP 1 LAST MATERIAL CHIP
J 0
(-5260 725);
DISPLAY 0.617021 (-5260 725);
PAINT SKYBLUE (-5260 725);
FORCEPROP 1 LAST PACK_TYPE 0402
J 0
(-5260 625);
DISPLAY 0.617021 (-5260 625);
PAINT SKYBLUE (-5260 625);
FORCEPROP 1 LASTPIN (-5300 900) $PN 1
J 0
(-5295 862);
DISPLAY 0.617021 (-5295 862);
PAINT ORANGE (-5295 862);
FORCEPROP 1 LAST TOLERANCE 1%
J 0
(-5255 825);
DISPLAY 0.617021 (-5255 825);
PAINT SKYBLUE (-5255 825);
FORCEPROP 1 LAST WATTAGE 1/16W
J 0
(-5260 775);
DISPLAY 0.617021 (-5260 775);
PAINT SKYBLUE (-5260 775);
FORCEPROP 1 LAST VALUE 40.2K
J 0
(-5255 875);
DISPLAY 0.617021 (-5255 875);
PAINT SKYBLUE (-5255 875);
FORCEPROP 1 LAST PART_NUMBER G21796-133
J 0
(-5260 675);
DISPLAY 0.617021 (-5260 675);
PAINT BLUE (-5260 675);
FORCEPROP 1 LAST LOCATION R1D40
J 0
(-5255 925);
DISPLAY 0.617021 (-5255 925);
PAINT AQUA (-5255 925);
FORCEPROP 2 LAST CDS_LIB mstr_discrete
J 0
(-5300 800);
PAINT ORANGE (-5300 800);
DISPLAY INVISIBLE (-5300 800);
FORCEPROP 2 LAST CDS_LOCATION R1D40
J 0
(-5255 925);
DISPLAY 0.617021 (-5255 925);
PAINT AQUA (-5255 925);
DISPLAY INVISIBLE (-5255 925);
FORCEPROP 1 LAST PATH I100
J 0
(-5250 975);
DISPLAY 0.978723 (-5250 975);
PAINT WHITE (-5250 975);
DISPLAY INVISIBLE (-5250 975);
FORCEPROP 0 LAST ROOM HOT_SWAP
J 0
(-5250 975);
DISPLAY 1.021277 (-5250 975);
PAINT ORANGE (-5250 975);
DISPLAY INVISIBLE (-5250 975);
FORCEPROP 2 LAST SEC 1
J 0
(-5250 1025);
DISPLAY 0.680851 (-5250 1025);
PAINT MONO (-5250 1025);
DISPLAY INVISIBLE (-5250 1025);
FORCEPROP 2 LAST SEC_TYPE 0402
J 0
(-5250 1025);
DISPLAY 1.021277 (-5250 1025);
PAINT ORANGE (-5250 1025);
DISPLAY INVISIBLE (-5250 1025);
FORCEADD AGND0..1
(-5400 450);
FORCEPROP 3 LASTPIN (-5400 500) SIG_NAME AGND_HSC\g
J 0
(-5390 510);
DISPLAY 0.659574 (-5390 510);
PAINT MONO (-5390 510);
DISPLAY INVISIBLE (-5390 510);
FORCEPROP 1 LAST HDL_POWER AGND_HSC
J 1
(-5400 400);
DISPLAY 0.617021 (-5400 400);
PAINT GREEN (-5400 400);
FORCEPROP 2 LAST ROOM VR_P3V3
J 0
(-5425 425);
PAINT ORANGE (-5425 425);
DISPLAY INVISIBLE (-5425 425);
FORCEPROP 1 LAST PATH I101
J 0
(-5325 450);
DISPLAY 0.872340 (-5325 450);
PAINT AQUA (-5325 450);
DISPLAY INVISIBLE (-5325 450);
FORCEPROP 1 LAST BODY_TYPE PLUMBING
J 0
(-5445 407);
DISPLAY 0.340426 (-5445 407);
PAINT GREEN (-5445 407);
DISPLAY INVISIBLE (-5445 407);
FORCEPROP 2 LAST CDS_LIB mstr_symbols
J 0
(-5400 450);
PAINT MONO (-5400 450);
DISPLAY INVISIBLE (-5400 450);
FORCEPROP 2 LAST BOM_COST MIO_VRD_MAIN
J 0
(-5375 425);
PAINT ORANGE (-5375 425);
DISPLAY INVISIBLE (-5375 425);
FORCEPROP 1 LAST VOLTAGE 0
J 0
(-5400 450);
PAINT SKYBLUE (-5400 450);
DISPLAY INVISIBLE (-5400 450);
FORCEADD RES..2
(-5600 750);
FORCEPROP 1 LASTPIN (-5600 650) $PN 2
J 0
(-5595 660);
DISPLAY 0.617021 (-5595 660);
PAINT ORANGE (-5595 660);
FORCEPROP 1 LAST PACK_TYPE 0402
J 0
(-5560 575);
DISPLAY 0.617021 (-5560 575);
PAINT SKYBLUE (-5560 575);
FORCEPROP 1 LAST MATERIAL CHIP
J 0
(-5560 675);
DISPLAY 0.617021 (-5560 675);
PAINT SKYBLUE (-5560 675);
FORCEPROP 1 LAST WATTAGE 1/16W
J 0
(-5560 725);
DISPLAY 0.617021 (-5560 725);
PAINT SKYBLUE (-5560 725);
FORCEPROP 1 LASTPIN (-5600 850) $PN 1
J 0
(-5595 812);
DISPLAY 0.617021 (-5595 812);
PAINT ORANGE (-5595 812);
FORCEPROP 1 LAST VALUE 16K
J 0
(-5555 825);
DISPLAY 0.617021 (-5555 825);
PAINT SKYBLUE (-5555 825);
FORCEPROP 1 LAST LOCATION R1D34
J 0
(-5555 875);
DISPLAY 0.617021 (-5555 875);
PAINT AQUA (-5555 875);
FORCEPROP 1 LAST TOLERANCE 1.0%
J 0
(-5555 775);
DISPLAY 0.617021 (-5555 775);
PAINT SKYBLUE (-5555 775);
FORCEPROP 1 LAST PART_NUMBER G21796-317
J 0
(-5585 625);
DISPLAY 0.617021 (-5585 625);
PAINT BLUE (-5585 625);
FORCEPROP 2 LAST CDS_LIB mstr_discrete
J 0
(-5600 750);
PAINT MONO (-5600 750);
DISPLAY INVISIBLE (-5600 750);
FORCEPROP 2 LAST CDS_LOCATION R1D34
J 0
(-5555 875);
DISPLAY 0.617021 (-5555 875);
PAINT AQUA (-5555 875);
DISPLAY INVISIBLE (-5555 875);
FORCEPROP 0 LAST ROOM HOT_SWAP
J 0
(-5550 925);
DISPLAY 1.021277 (-5550 925);
PAINT ORANGE (-5550 925);
DISPLAY INVISIBLE (-5550 925);
FORCEPROP 1 LAST PATH I102
J 0
(-5550 925);
DISPLAY 0.978723 (-5550 925);
PAINT WHITE (-5550 925);
DISPLAY INVISIBLE (-5550 925);
FORCEPROP 2 LAST SEC_TYPE 0402
J 0
(-5550 975);
DISPLAY 1.021277 (-5550 975);
PAINT ORANGE (-5550 975);
DISPLAY INVISIBLE (-5550 975);
FORCEPROP 2 LAST SEC 1
J 0
(-5550 975);
DISPLAY 0.680851 (-5550 975);
PAINT MONO (-5550 975);
DISPLAY INVISIBLE (-5550 975);
FORCEADD CAP_A..1
R 2
(-6150 850);
FORCEPROP 1 LAST PART_NUMBER A36096-030
J 2
(-6200 700);
DISPLAY 0.617021 (-6200 700);
PAINT BLUE (-6200 700);
FORCEPROP 1 LAST PACK_TYPE 0402V
J 2
(-6200 650);
DISPLAY 0.617021 (-6200 650);
PAINT SKYBLUE (-6200 650);
FORCEPROP 1 LAST MATERIAL X7R
J 2
(-6200 750);
DISPLAY 0.617021 (-6200 750);
PAINT SKYBLUE (-6200 750);
FORCEPROP 1 LAST VOLTAGE 16V
J 2
(-6200 850);
DISPLAY 0.617021 (-6200 850);
PAINT SKYBLUE (-6200 850);
FORCEPROP 1 LAST LOCATION C9P15
J 2
(-6200 950);
DISPLAY 0.617021 (-6200 950);
PAINT AQUA (-6200 950);
FORCEPROP 1 LAST VALUE 0.1UF
J 2
(-6200 900);
DISPLAY 0.617021 (-6200 900);
PAINT SKYBLUE (-6200 900);
FORCEPROP 1 LAST TOLERANCE 10%
J 2
(-6200 800);
DISPLAY 0.617021 (-6200 800);
PAINT SKYBLUE (-6200 800);
FORCEPROP 1 LASTPIN (-6150 750) $PN 2
J 2
(-6160 730);
DISPLAY 0.787234 (-6160 730);
PAINT ORANGE (-6160 730);
DISPLAY INVISIBLE (-6160 730);
FORCEPROP 2 LAST CDS_LOCATION C9P15
J 2
(-6200 950);
DISPLAY 0.617021 (-6200 950);
PAINT AQUA (-6200 950);
DISPLAY INVISIBLE (-6200 950);
FORCEPROP 2 LAST CDS_LIB dev_discrete
J 0
(-6150 850);
PAINT ORANGE (-6150 850);
DISPLAY INVISIBLE (-6150 850);
FORCEPROP 1 LASTPIN (-6150 950) $PN 1
J 2
(-6160 930);
DISPLAY 0.787234 (-6160 930);
PAINT ORANGE (-6160 930);
DISPLAY INVISIBLE (-6160 930);
FORCEPROP 0 LAST ROOM HOT_SWAP
J 0
(-6200 1000);
DISPLAY 1.021277 (-6200 1000);
PAINT ORANGE (-6200 1000);
DISPLAY INVISIBLE (-6200 1000);
FORCEPROP 1 LAST PATH I105
J 2
(-6200 1000);
DISPLAY 0.978723 (-6200 1000);
PAINT WHITE (-6200 1000);
DISPLAY INVISIBLE (-6200 1000);
FORCEPROP 2 LAST $SEC 1
J 0
(-6200 1050);
PAINT MONO (-6200 1050);
DISPLAY INVISIBLE (-6200 1050);
FORCEPROP 2 LAST CDS_SEC 1
J 0
(-6200 1050);
PAINT MONO (-6200 1050);
DISPLAY INVISIBLE (-6200 1050);
FORCEADD AGND0..1
(-6150 600);
FORCEPROP 3 LASTPIN (-6150 650) SIG_NAME AGND_HSC\g
J 0
(-6140 660);
DISPLAY 0.659574 (-6140 660);
PAINT MONO (-6140 660);
DISPLAY INVISIBLE (-6140 660);
FORCEPROP 1 LAST HDL_POWER AGND_HSC
J 1
(-6150 550);
DISPLAY 0.617021 (-6150 550);
PAINT GREEN (-6150 550);
FORCEPROP 1 LAST VOLTAGE 0
J 0
(-6150 600);
PAINT SKYBLUE (-6150 600);
DISPLAY INVISIBLE (-6150 600);
FORCEPROP 2 LAST CDS_LIB mstr_symbols
J 0
(-6150 600);
PAINT MONO (-6150 600);
DISPLAY INVISIBLE (-6150 600);
FORCEPROP 1 LAST BODY_TYPE PLUMBING
J 0
(-6195 557);
DISPLAY 0.340426 (-6195 557);
PAINT GREEN (-6195 557);
DISPLAY INVISIBLE (-6195 557);
FORCEPROP 2 LAST ROOM VR_P3V3
J 0
(-6175 575);
PAINT ORANGE (-6175 575);
DISPLAY INVISIBLE (-6175 575);
FORCEPROP 1 LAST PATH I106
J 0
(-6075 600);
DISPLAY 0.872340 (-6075 600);
PAINT AQUA (-6075 600);
DISPLAY INVISIBLE (-6075 600);
FORCEPROP 2 LAST BOM_COST MIO_VRD_MAIN
J 0
(-6125 575);
PAINT ORANGE (-6125 575);
DISPLAY INVISIBLE (-6125 575);
FORCEADD CAP_A..1
R 2
(-6075 3575);
FORCEPROP 1 LAST MATERIAL X7R
J 2
(-6125 3475);
DISPLAY 0.617021 (-6125 3475);
PAINT SKYBLUE (-6125 3475);
FORCEPROP 1 LAST VOLTAGE 16V
J 2
(-6125 3575);
DISPLAY 0.617021 (-6125 3575);
PAINT SKYBLUE (-6125 3575);
FORCEPROP 1 LAST PACK_TYPE 0402V
J 2
(-6125 3375);
DISPLAY 0.617021 (-6125 3375);
PAINT SKYBLUE (-6125 3375);
FORCEPROP 1 LAST TOLERANCE 10%
J 2
(-6125 3525);
DISPLAY 0.617021 (-6125 3525);
PAINT SKYBLUE (-6125 3525);
FORCEPROP 1 LAST VALUE 0.1UF
J 2
(-6125 3625);
DISPLAY 0.617021 (-6125 3625);
PAINT SKYBLUE (-6125 3625);
FORCEPROP 1 LAST PART_NUMBER A36096-030
J 2
(-6125 3425);
DISPLAY 0.617021 (-6125 3425);
PAINT BLUE (-6125 3425);
FORCEPROP 1 LAST LOCATION C1D26
J 2
(-6125 3675);
DISPLAY 0.617021 (-6125 3675);
PAINT AQUA (-6125 3675);
FORCEPROP 1 LASTPIN (-6075 3475) $PN 2
J 2
(-6085 3455);
DISPLAY 0.617021 (-6085 3455);
PAINT ORANGE (-6085 3455);
FORCEPROP 1 LASTPIN (-6075 3675) $PN 1
J 2
(-6085 3655);
DISPLAY 0.617021 (-6085 3655);
PAINT ORANGE (-6085 3655);
FORCEPROP 2 LAST CDS_LIB dev_discrete
J 0
(-6075 3575);
PAINT ORANGE (-6075 3575);
DISPLAY INVISIBLE (-6075 3575);
FORCEPROP 2 LAST CDS_LOCATION C1D26
J 2
(-6125 3675);
DISPLAY 0.617021 (-6125 3675);
PAINT AQUA (-6125 3675);
DISPLAY INVISIBLE (-6125 3675);
FORCEPROP 0 LAST ROOM HOT_SWAP
J 0
(-6125 3725);
DISPLAY 1.021277 (-6125 3725);
PAINT ORANGE (-6125 3725);
DISPLAY INVISIBLE (-6125 3725);
FORCEPROP 1 LAST PATH I107
J 2
(-6125 3725);
DISPLAY 0.978723 (-6125 3725);
PAINT WHITE (-6125 3725);
DISPLAY INVISIBLE (-6125 3725);
FORCEPROP 2 LAST CDS_SEC 1
J 0
(-6125 3725);
PAINT ORANGE (-6125 3725);
DISPLAY INVISIBLE (-6125 3725);
FORCEPROP 2 LAST SEC_TYPE 0402V
J 0
(-6125 3775);
DISPLAY 1.021277 (-6125 3775);
PAINT ORANGE (-6125 3775);
DISPLAY INVISIBLE (-6125 3775);
FORCEPROP 2 LAST SEC 1
J 0
(-6125 3775);
DISPLAY 0.680851 (-6125 3775);
PAINT MONO (-6125 3775);
DISPLAY INVISIBLE (-6125 3775);
FORCEADD RES..1
(-2050 925);
FORCEPROP 1 LASTPIN (-2150 925) $PN 1
J 0
(-2138 937);
DISPLAY 0.617021 (-2138 937);
PAINT ORANGE (-2138 937);
FORCEPROP 1 LAST WATTAGE 1/16W
J 2
(-2075 775);
DISPLAY 0.617021 (-2075 775);
PAINT SKYBLUE (-2075 775);
FORCEPROP 1 LAST VALUE 33.2
J 2
(-2075 825);
DISPLAY 0.617021 (-2075 825);
PAINT SKYBLUE (-2075 825);
FORCEPROP 1 LAST MATERIAL CHIP
J 0
(-2050 775);
DISPLAY 0.617021 (-2050 775);
PAINT SKYBLUE (-2050 775);
FORCEPROP 1 LAST TOLERANCE 1%
J 0
(-2050 825);
DISPLAY 0.617021 (-2050 825);
PAINT SKYBLUE (-2050 825);
FORCEPROP 1 LAST PART_NUMBER G21796-074
J 0
(-2100 1025);
DISPLAY 0.617021 (-2100 1025);
PAINT BLUE (-2100 1025);
FORCEPROP 1 LAST LOCATION R1D33
J 0
(-2100 975);
DISPLAY 0.617021 (-2100 975);
PAINT AQUA (-2100 975);
FORCEPROP 1 LASTPIN (-1950 925) $PN 2
J 0
(-1988 937);
DISPLAY 0.617021 (-1988 937);
PAINT ORANGE (-1988 937);
FORCEPROP 1 LAST PACK_TYPE 0402
J 0
(-1800 775);
DISPLAY 0.617021 (-1800 775);
PAINT SKYBLUE (-1800 775);
FORCEPROP 2 LAST CDS_LOCATION R1D33
J 0
(-2100 975);
DISPLAY 0.617021 (-2100 975);
PAINT AQUA (-2100 975);
DISPLAY INVISIBLE (-2100 975);
FORCEPROP 2 LAST CDS_LIB mstr_discrete
J 0
(-2050 925);
PAINT MONO (-2050 925);
DISPLAY INVISIBLE (-2050 925);
FORCEPROP 1 LAST PATH I108
J 0
(-2100 1075);
DISPLAY 0.978723 (-2100 1075);
PAINT WHITE (-2100 1075);
DISPLAY INVISIBLE (-2100 1075);
FORCEPROP 2 LAST SEC 1
J 0
(-2100 1125);
DISPLAY 0.680851 (-2100 1125);
PAINT MONO (-2100 1125);
DISPLAY INVISIBLE (-2100 1125);
FORCEPROP 2 LAST SEC_TYPE 0402
J 0
(-2100 1125);
DISPLAY 1.021277 (-2100 1125);
PAINT ORANGE (-2100 1125);
DISPLAY INVISIBLE (-2100 1125);
FORCEADD RES..1
(-1700 3950);
FORCEPROP 1 LAST WATTAGE 1/16W
J 2
(-1725 3800);
DISPLAY 0.617021 (-1725 3800);
PAINT SKYBLUE (-1725 3800);
FORCEPROP 1 LAST VALUE 33.2
J 2
(-1725 3850);
DISPLAY 0.617021 (-1725 3850);
PAINT SKYBLUE (-1725 3850);
FORCEPROP 1 LAST MATERIAL CHIP
J 0
(-1700 3800);
DISPLAY 0.617021 (-1700 3800);
PAINT SKYBLUE (-1700 3800);
FORCEPROP 1 LASTPIN (-1800 3950) $PN 1
J 0
(-1788 3962);
DISPLAY 0.617021 (-1788 3962);
PAINT ORANGE (-1788 3962);
FORCEPROP 1 LAST LOCATION R1D26
J 0
(-1750 4000);
DISPLAY 0.617021 (-1750 4000);
PAINT AQUA (-1750 4000);
FORCEPROP 1 LAST TOLERANCE 1%
J 0
(-1700 3850);
DISPLAY 0.617021 (-1700 3850);
PAINT SKYBLUE (-1700 3850);
FORCEPROP 1 LASTPIN (-1600 3950) $PN 2
J 0
(-1638 3962);
DISPLAY 0.617021 (-1638 3962);
PAINT ORANGE (-1638 3962);
FORCEPROP 1 LAST PART_NUMBER G21796-074
J 0
(-1575 3850);
DISPLAY 0.617021 (-1575 3850);
PAINT BLUE (-1575 3850);
FORCEPROP 1 LAST PACK_TYPE 0402
J 0
(-1450 3800);
DISPLAY 0.617021 (-1450 3800);
PAINT SKYBLUE (-1450 3800);
FORCEPROP 2 LAST CDS_LIB mstr_discrete
J 0
(-1700 3950);
PAINT MONO (-1700 3950);
DISPLAY INVISIBLE (-1700 3950);
FORCEPROP 2 LAST CDS_LOCATION R1D26
J 0
(-1750 4000);
DISPLAY 0.617021 (-1750 4000);
PAINT AQUA (-1750 4000);
DISPLAY INVISIBLE (-1750 4000);
FORCEPROP 1 LAST PATH I109
J 0
(-1750 4100);
DISPLAY 0.978723 (-1750 4100);
PAINT WHITE (-1750 4100);
DISPLAY INVISIBLE (-1750 4100);
FORCEPROP 2 LAST SEC 1
J 0
(-1750 4150);
DISPLAY 0.680851 (-1750 4150);
PAINT MONO (-1750 4150);
DISPLAY INVISIBLE (-1750 4150);
FORCEPROP 2 LAST SEC_TYPE 0402
J 0
(-1750 4150);
DISPLAY 1.021277 (-1750 4150);
PAINT ORANGE (-1750 4150);
DISPLAY INVISIBLE (-1750 4150);
FORCEADD GND..1
(-2150 2275);
FORCEPROP 3 LASTPIN (-2150 2325) SIG_NAME GND\g
J 0
(-2140 2335);
DISPLAY 0.659574 (-2140 2335);
PAINT MONO (-2140 2335);
DISPLAY INVISIBLE (-2140 2335);
FORCEPROP 1 LAST SIZE 1B
J 0
(-2075 2225);
DISPLAY 0.638298 (-2075 2225);
PAINT GREEN (-2075 2225);
DISPLAY INVISIBLE (-2075 2225);
FORCEPROP 1 LAST BODY_TYPE PLUMBING
J 0
(-2195 2232);
DISPLAY 0.340426 (-2195 2232);
PAINT GREEN (-2195 2232);
DISPLAY INVISIBLE (-2195 2232);
FORCEPROP 1 LAST VOLTAGE 0
J 0
(-2150 2275);
PAINT SKYBLUE (-2150 2275);
DISPLAY INVISIBLE (-2150 2275);
FORCEPROP 2 LAST CDS_LIB mstr_symbols
J 0
(-2150 2275);
PAINT ORANGE (-2150 2275);
DISPLAY INVISIBLE (-2150 2275);
FORCEPROP 1 LAST PATH I11
J 0
(-2075 2275);
DISPLAY 0.872340 (-2075 2275);
PAINT AQUA (-2075 2275);
DISPLAY INVISIBLE (-2075 2275);
FORCEPROP 1 LAST HDL_POWER GND
J 0
(-2150 2425);
DISPLAY 0.638298 (-2150 2425);
PAINT GREEN (-2150 2425);
DISPLAY INVISIBLE (-2150 2425);
FORCEADD RES..1
(-2050 1375);
FORCEPROP 1 LAST WATTAGE 1/16W
J 2
(-2075 1225);
DISPLAY 0.617021 (-2075 1225);
PAINT SKYBLUE (-2075 1225);
FORCEPROP 1 LAST VALUE 33.2
J 2
(-2075 1275);
DISPLAY 0.617021 (-2075 1275);
PAINT SKYBLUE (-2075 1275);
FORCEPROP 1 LASTPIN (-2150 1375) $PN 1
J 0
(-2138 1387);
DISPLAY 0.617021 (-2138 1387);
PAINT ORANGE (-2138 1387);
FORCEPROP 1 LAST MATERIAL CHIP
J 0
(-2050 1225);
DISPLAY 0.617021 (-2050 1225);
PAINT SKYBLUE (-2050 1225);
FORCEPROP 1 LAST TOLERANCE 1%
J 0
(-2050 1275);
DISPLAY 0.617021 (-2050 1275);
PAINT SKYBLUE (-2050 1275);
FORCEPROP 1 LAST PART_NUMBER G21796-074
J 0
(-2250 1175);
DISPLAY 0.617021 (-2250 1175);
PAINT BLUE (-2250 1175);
FORCEPROP 1 LAST LOCATION R1D30
J 0
(-2100 1425);
DISPLAY 0.617021 (-2100 1425);
PAINT AQUA (-2100 1425);
FORCEPROP 1 LASTPIN (-1950 1375) $PN 2
J 0
(-1988 1387);
DISPLAY 0.617021 (-1988 1387);
PAINT ORANGE (-1988 1387);
FORCEPROP 1 LAST PACK_TYPE 0402
J 0
(-1800 1225);
DISPLAY 0.617021 (-1800 1225);
PAINT SKYBLUE (-1800 1225);
FORCEPROP 2 LAST CDS_LIB mstr_discrete
J 0
(-2050 1375);
PAINT MONO (-2050 1375);
DISPLAY INVISIBLE (-2050 1375);
FORCEPROP 2 LAST CDS_LOCATION R1D30
J 0
(-2100 1425);
DISPLAY 0.617021 (-2100 1425);
PAINT AQUA (-2100 1425);
DISPLAY INVISIBLE (-2100 1425);
FORCEPROP 1 LAST PATH I110
J 0
(-2100 1525);
DISPLAY 0.978723 (-2100 1525);
PAINT WHITE (-2100 1525);
DISPLAY INVISIBLE (-2100 1525);
FORCEPROP 2 LAST SEC_TYPE 0402
J 0
(-2100 1575);
DISPLAY 1.021277 (-2100 1575);
PAINT ORANGE (-2100 1575);
DISPLAY INVISIBLE (-2100 1575);
FORCEPROP 2 LAST SEC 1
J 0
(-2100 1575);
DISPLAY 0.680851 (-2100 1575);
PAINT MONO (-2100 1575);
DISPLAY INVISIBLE (-2100 1575);
FORCEADD AGND0..1
(-6600 -25);
FORCEPROP 3 LASTPIN (-6600 25) SIG_NAME AGND_HSC\g
J 0
(-6590 35);
DISPLAY 0.659574 (-6590 35);
PAINT MONO (-6590 35);
DISPLAY INVISIBLE (-6590 35);
FORCEPROP 1 LAST HDL_POWER AGND_HSC
J 1
(-6600 -75);
DISPLAY 0.617021 (-6600 -75);
PAINT GREEN (-6600 -75);
FORCEPROP 2 LAST ROOM VR_P3V3
J 0
(-6625 -50);
PAINT ORANGE (-6625 -50);
DISPLAY INVISIBLE (-6625 -50);
FORCEPROP 1 LAST BODY_TYPE PLUMBING
J 0
(-6645 -68);
DISPLAY 0.340426 (-6645 -68);
PAINT GREEN (-6645 -68);
DISPLAY INVISIBLE (-6645 -68);
FORCEPROP 2 LAST BOM_COST MIO_VRD_MAIN
J 0
(-6575 -50);
PAINT ORANGE (-6575 -50);
DISPLAY INVISIBLE (-6575 -50);
FORCEPROP 1 LAST PATH I112
J 0
(-6525 -25);
DISPLAY 0.872340 (-6525 -25);
PAINT AQUA (-6525 -25);
DISPLAY INVISIBLE (-6525 -25);
FORCEPROP 2 LAST CDS_LIB mstr_symbols
J 0
(-6600 -25);
PAINT MONO (-6600 -25);
DISPLAY INVISIBLE (-6600 -25);
FORCEPROP 1 LAST VOLTAGE 0
J 0
(-6600 -25);
PAINT SKYBLUE (-6600 -25);
DISPLAY INVISIBLE (-6600 -25);
FORCEADD AGND0..1
(-7200 3250);
FORCEPROP 3 LASTPIN (-7200 3300) SIG_NAME AGND_HSC\g
J 0
(-7190 3310);
DISPLAY 0.659574 (-7190 3310);
PAINT MONO (-7190 3310);
DISPLAY INVISIBLE (-7190 3310);
FORCEPROP 1 LAST HDL_POWER AGND_HSC
J 1
(-7200 3200);
DISPLAY 0.617021 (-7200 3200);
PAINT GREEN (-7200 3200);
FORCEPROP 1 LAST BODY_TYPE PLUMBING
J 0
(-7245 3207);
DISPLAY 0.340426 (-7245 3207);
PAINT GREEN (-7245 3207);
DISPLAY INVISIBLE (-7245 3207);
FORCEPROP 2 LAST BOM_COST MIO_VRD_MAIN
J 0
(-7175 3225);
PAINT ORANGE (-7175 3225);
DISPLAY INVISIBLE (-7175 3225);
FORCEPROP 1 LAST VOLTAGE 0
J 0
(-7200 3250);
PAINT SKYBLUE (-7200 3250);
DISPLAY INVISIBLE (-7200 3250);
FORCEPROP 2 LAST ROOM VR_P3V3
J 0
(-7225 3225);
PAINT ORANGE (-7225 3225);
DISPLAY INVISIBLE (-7225 3225);
FORCEPROP 2 LAST CDS_LIB mstr_symbols
J 0
(-7200 3250);
PAINT ORANGE (-7200 3250);
DISPLAY INVISIBLE (-7200 3250);
FORCEPROP 1 LAST PATH I113
J 0
(-7125 3250);
DISPLAY 0.872340 (-7125 3250);
PAINT AQUA (-7125 3250);
DISPLAY INVISIBLE (-7125 3250);
FORCEADD AGND0..1
(-5525 3350);
FORCEPROP 3 LASTPIN (-5525 3400) SIG_NAME AGND_HSC\g
J 0
(-5515 3410);
DISPLAY 0.659574 (-5515 3410);
PAINT MONO (-5515 3410);
DISPLAY INVISIBLE (-5515 3410);
FORCEPROP 1 LAST HDL_POWER AGND_HSC
J 1
(-5525 3300);
DISPLAY 0.617021 (-5525 3300);
PAINT GREEN (-5525 3300);
FORCEPROP 1 LAST BODY_TYPE PLUMBING
J 0
(-5570 3307);
DISPLAY 0.340426 (-5570 3307);
PAINT GREEN (-5570 3307);
DISPLAY INVISIBLE (-5570 3307);
FORCEPROP 2 LAST ROOM VR_P3V3
J 0
(-5550 3325);
PAINT ORANGE (-5550 3325);
DISPLAY INVISIBLE (-5550 3325);
FORCEPROP 2 LAST BOM_COST MIO_VRD_MAIN
J 0
(-5500 3325);
PAINT ORANGE (-5500 3325);
DISPLAY INVISIBLE (-5500 3325);
FORCEPROP 1 LAST VOLTAGE 0
J 0
(-5525 3350);
PAINT SKYBLUE (-5525 3350);
DISPLAY INVISIBLE (-5525 3350);
FORCEPROP 2 LAST CDS_LIB mstr_symbols
J 0
(-5525 3350);
PAINT ORANGE (-5525 3350);
DISPLAY INVISIBLE (-5525 3350);
FORCEPROP 1 LAST PATH I115
J 0
(-5450 3350);
DISPLAY 0.872340 (-5450 3350);
PAINT AQUA (-5450 3350);
DISPLAY INVISIBLE (-5450 3350);
FORCEADD GND..1
(-5100 3400);
FORCEPROP 3 LASTPIN (-5100 3450) SIG_NAME GND\g
J 0
(-5090 3460);
DISPLAY 0.659574 (-5090 3460);
PAINT MONO (-5090 3460);
DISPLAY INVISIBLE (-5090 3460);
FORCEPROP 1 LAST BODY_TYPE PLUMBING
J 0
(-5145 3357);
DISPLAY 0.340426 (-5145 3357);
PAINT GREEN (-5145 3357);
DISPLAY INVISIBLE (-5145 3357);
FORCEPROP 1 LAST HDL_POWER GND
J 0
(-5100 3550);
DISPLAY 0.638298 (-5100 3550);
PAINT GREEN (-5100 3550);
DISPLAY INVISIBLE (-5100 3550);
FORCEPROP 1 LAST PATH I116
J 0
(-5025 3400);
DISPLAY 0.872340 (-5025 3400);
PAINT AQUA (-5025 3400);
DISPLAY INVISIBLE (-5025 3400);
FORCEPROP 2 LAST CDS_LIB mstr_symbols
J 0
(-5100 3400);
PAINT ORANGE (-5100 3400);
DISPLAY INVISIBLE (-5100 3400);
FORCEPROP 1 LAST SIZE 1B
J 0
(-5025 3350);
DISPLAY 0.638298 (-5025 3350);
PAINT GREEN (-5025 3350);
DISPLAY INVISIBLE (-5025 3350);
FORCEPROP 1 LAST VOLTAGE 0
J 0
(-5100 3400);
PAINT SKYBLUE (-5100 3400);
DISPLAY INVISIBLE (-5100 3400);
FORCEADD AGND0..1
(-6375 3275);
FORCEPROP 3 LASTPIN (-6375 3325) SIG_NAME AGND_HSC\g
J 0
(-6365 3335);
DISPLAY 0.659574 (-6365 3335);
PAINT MONO (-6365 3335);
DISPLAY INVISIBLE (-6365 3335);
FORCEPROP 1 LAST HDL_POWER AGND_HSC
J 1
(-6375 3225);
DISPLAY 0.617021 (-6375 3225);
PAINT GREEN (-6375 3225);
FORCEPROP 1 LAST BODY_TYPE PLUMBING
J 0
(-6420 3232);
DISPLAY 0.340426 (-6420 3232);
PAINT GREEN (-6420 3232);
DISPLAY INVISIBLE (-6420 3232);
FORCEPROP 2 LAST ROOM VR_P3V3
J 0
(-6400 3250);
PAINT ORANGE (-6400 3250);
DISPLAY INVISIBLE (-6400 3250);
FORCEPROP 1 LAST VOLTAGE 0
J 0
(-6375 3275);
PAINT SKYBLUE (-6375 3275);
DISPLAY INVISIBLE (-6375 3275);
FORCEPROP 2 LAST CDS_LIB mstr_symbols
J 0
(-6375 3275);
PAINT ORANGE (-6375 3275);
DISPLAY INVISIBLE (-6375 3275);
FORCEPROP 2 LAST BOM_COST MIO_VRD_MAIN
J 0
(-6350 3250);
PAINT ORANGE (-6350 3250);
DISPLAY INVISIBLE (-6350 3250);
FORCEPROP 1 LAST PATH I117
J 0
(-6300 3275);
DISPLAY 0.872340 (-6300 3275);
PAINT AQUA (-6300 3275);
DISPLAY INVISIBLE (-6300 3275);
FORCEADD AGND0..1
(-2375 2300);
FORCEPROP 3 LASTPIN (-2375 2350) SIG_NAME AGND_HSC\g
J 0
(-2365 2360);
DISPLAY 0.659574 (-2365 2360);
PAINT MONO (-2365 2360);
DISPLAY INVISIBLE (-2365 2360);
FORCEPROP 1 LAST HDL_POWER AGND_HSC
J 1
(-2375 2250);
DISPLAY 0.617021 (-2375 2250);
PAINT GREEN (-2375 2250);
FORCEPROP 1 LAST BODY_TYPE PLUMBING
J 0
(-2420 2257);
DISPLAY 0.340426 (-2420 2257);
PAINT GREEN (-2420 2257);
DISPLAY INVISIBLE (-2420 2257);
FORCEPROP 1 LAST VOLTAGE 0
J 0
(-2375 2300);
PAINT SKYBLUE (-2375 2300);
DISPLAY INVISIBLE (-2375 2300);
FORCEPROP 2 LAST BOM_COST MIO_VRD_MAIN
J 0
(-2350 2275);
PAINT ORANGE (-2350 2275);
DISPLAY INVISIBLE (-2350 2275);
FORCEPROP 2 LAST CDS_LIB mstr_symbols
J 0
(-2375 2300);
PAINT ORANGE (-2375 2300);
DISPLAY INVISIBLE (-2375 2300);
FORCEPROP 2 LAST ROOM VR_P3V3
J 0
(-2400 2275);
PAINT ORANGE (-2400 2275);
DISPLAY INVISIBLE (-2400 2275);
FORCEPROP 1 LAST PATH I118
J 0
(-2300 2300);
DISPLAY 0.872340 (-2300 2300);
PAINT AQUA (-2300 2300);
DISPLAY INVISIBLE (-2300 2300);
FORCEADD CAP..1
(-5650 2000);
FORCEPROP 1 LASTPIN (-5650 1900) $PN 2
J 0
(-5640 1880);
DISPLAY 0.617021 (-5640 1880);
PAINT ORANGE (-5640 1880);
FORCEPROP 1 LAST MATERIAL X6S
J 0
(-5600 1900);
DISPLAY 0.617021 (-5600 1900);
PAINT SKYBLUE (-5600 1900);
FORCEPROP 1 LAST VOLTAGE 16V
J 0
(-5600 2000);
DISPLAY 0.617021 (-5600 2000);
PAINT SKYBLUE (-5600 2000);
FORCEPROP 1 LAST TOLERANCE 10%
J 0
(-5600 1950);
DISPLAY 0.617021 (-5600 1950);
PAINT SKYBLUE (-5600 1950);
FORCEPROP 1 LAST PACK_TYPE 0402
J 0
(-5425 1825);
DISPLAY 0.617021 (-5425 1825);
PAINT SKYBLUE (-5425 1825);
FORCEPROP 1 LAST PART_NUMBER D97712-011
J 0
(-5600 1850);
DISPLAY 0.617021 (-5600 1850);
PAINT BLUE (-5600 1850);
FORCEPROP 1 LASTPIN (-5650 2100) $PN 1
J 0
(-5640 2080);
DISPLAY 0.617021 (-5640 2080);
PAINT ORANGE (-5640 2080);
FORCEPROP 1 LAST VALUE 1.0UF
J 0
(-5600 2050);
DISPLAY 0.617021 (-5600 2050);
PAINT SKYBLUE (-5600 2050);
FORCEPROP 1 LAST LOCATION C1D19
J 0
(-5600 2100);
DISPLAY 0.617021 (-5600 2100);
PAINT AQUA (-5600 2100);
FORCEPROP 2 LAST CDS_LIB mstr_discrete
J 0
(-5650 2000);
PAINT ORANGE (-5650 2000);
DISPLAY INVISIBLE (-5650 2000);
FORCEPROP 0 LAST ROOM HOT_SWAP
J 0
(-5600 2150);
DISPLAY 1.021277 (-5600 2150);
PAINT ORANGE (-5600 2150);
DISPLAY INVISIBLE (-5600 2150);
FORCEPROP 1 LAST PATH I119
J 0
(-5600 2150);
DISPLAY 0.978723 (-5600 2150);
PAINT WHITE (-5600 2150);
DISPLAY INVISIBLE (-5600 2150);
FORCEPROP 2 LAST CDS_LOCATION C1D19
J 0
(-5600 2100);
DISPLAY 0.617021 (-5600 2100);
PAINT AQUA (-5600 2100);
DISPLAY INVISIBLE (-5600 2100);
FORCEPROP 2 LAST SEC 1
J 0
(-5600 2200);
DISPLAY 0.680851 (-5600 2200);
PAINT MONO (-5600 2200);
DISPLAY INVISIBLE (-5600 2200);
FORCEPROP 2 LAST SEC_TYPE 0402
J 0
(-5600 2200);
DISPLAY 1.021277 (-5600 2200);
PAINT ORANGE (-5600 2200);
DISPLAY INVISIBLE (-5600 2200);
FORCEADD RES..2
(-6500 4050);
FORCEPROP 1 LASTPIN (-6500 3950) $PN 2
J 0
(-6495 3960);
DISPLAY 0.617021 (-6495 3960);
PAINT ORANGE (-6495 3960);
FORCEPROP 1 LAST WATTAGE 1/16W
J 0
(-6460 4025);
DISPLAY 0.617021 (-6460 4025);
PAINT SKYBLUE (-6460 4025);
FORCEPROP 1 LAST MATERIAL CHIP
J 0
(-6460 3975);
DISPLAY 0.617021 (-6460 3975);
PAINT SKYBLUE (-6460 3975);
FORCEPROP 1 LAST PACK_TYPE 0402
J 0
(-6460 3875);
DISPLAY 0.617021 (-6460 3875);
PAINT SKYBLUE (-6460 3875);
FORCEPROP 1 LAST PART_NUMBER G21796-010
J 0
(-6460 3925);
DISPLAY 0.617021 (-6460 3925);
PAINT BLUE (-6460 3925);
FORCEPROP 1 LAST TOLERANCE 1%
J 0
(-6455 4075);
DISPLAY 0.617021 (-6455 4075);
PAINT SKYBLUE (-6455 4075);
FORCEPROP 1 LASTPIN (-6500 4150) $PN 1
J 0
(-6495 4112);
DISPLAY 0.617021 (-6495 4112);
PAINT ORANGE (-6495 4112);
FORCEPROP 1 LAST VALUE 100.0K
J 0
(-6455 4125);
DISPLAY 0.617021 (-6455 4125);
PAINT SKYBLUE (-6455 4125);
FORCEPROP 1 LAST LOCATION R9P29
J 0
(-6455 4175);
DISPLAY 0.617021 (-6455 4175);
PAINT AQUA (-6455 4175);
FORCEPROP 2 LAST CDS_LIB mstr_discrete
J 0
(-6500 4050);
PAINT ORANGE (-6500 4050);
DISPLAY INVISIBLE (-6500 4050);
FORCEPROP 2 LAST SEC_TYPE 0402
J 0
(-6450 4275);
DISPLAY 1.021277 (-6450 4275);
PAINT ORANGE (-6450 4275);
DISPLAY INVISIBLE (-6450 4275);
FORCEPROP 2 LAST SEC 1
J 0
(-6450 4275);
DISPLAY 0.680851 (-6450 4275);
PAINT MONO (-6450 4275);
DISPLAY INVISIBLE (-6450 4275);
FORCEPROP 2 LAST CDS_LOCATION R9P29
J 0
(-6455 4175);
DISPLAY 0.617021 (-6455 4175);
PAINT AQUA (-6455 4175);
DISPLAY INVISIBLE (-6455 4175);
FORCEPROP 1 LAST PATH I12
J 0
(-6450 4225);
DISPLAY 0.978723 (-6450 4225);
PAINT WHITE (-6450 4225);
DISPLAY INVISIBLE (-6450 4225);
FORCEPROP 0 LAST ROOM HOT_SWAP
J 0
(-6450 4225);
DISPLAY 1.021277 (-6450 4225);
PAINT ORANGE (-6450 4225);
DISPLAY INVISIBLE (-6450 4225);
FORCEADD AGND0..1
(-5650 1800);
FORCEPROP 3 LASTPIN (-5650 1850) SIG_NAME AGND_HSC\g
J 0
(-5640 1860);
DISPLAY 0.659574 (-5640 1860);
PAINT MONO (-5640 1860);
DISPLAY INVISIBLE (-5640 1860);
FORCEPROP 1 LAST HDL_POWER AGND_HSC
J 1
(-5650 1750);
DISPLAY 0.617021 (-5650 1750);
PAINT GREEN (-5650 1750);
FORCEPROP 1 LAST BODY_TYPE PLUMBING
J 0
(-5695 1757);
DISPLAY 0.340426 (-5695 1757);
PAINT GREEN (-5695 1757);
DISPLAY INVISIBLE (-5695 1757);
FORCEPROP 2 LAST ROOM VR_P3V3
J 0
(-5675 1775);
PAINT ORANGE (-5675 1775);
DISPLAY INVISIBLE (-5675 1775);
FORCEPROP 2 LAST CDS_LIB mstr_symbols
J 0
(-5650 1800);
PAINT ORANGE (-5650 1800);
DISPLAY INVISIBLE (-5650 1800);
FORCEPROP 1 LAST VOLTAGE 0
J 0
(-5650 1800);
PAINT SKYBLUE (-5650 1800);
DISPLAY INVISIBLE (-5650 1800);
FORCEPROP 2 LAST BOM_COST MIO_VRD_MAIN
J 0
(-5625 1775);
PAINT ORANGE (-5625 1775);
DISPLAY INVISIBLE (-5625 1775);
FORCEPROP 1 LAST PATH I120
J 0
(-5575 1800);
DISPLAY 0.872340 (-5575 1800);
PAINT AQUA (-5575 1800);
DISPLAY INVISIBLE (-5575 1800);
FORCEADD CAP_A..1
R 2
(-5000 425);
FORCEPROP 1 LAST MATERIAL X7R
J 2
(-5050 325);
DISPLAY 0.617021 (-5050 325);
PAINT SKYBLUE (-5050 325);
FORCEPROP 1 LAST VOLTAGE 16V
J 2
(-5050 425);
DISPLAY 0.617021 (-5050 425);
PAINT SKYBLUE (-5050 425);
FORCEPROP 1 LAST PACK_TYPE 0402V
J 2
(-5050 225);
DISPLAY 0.617021 (-5050 225);
PAINT SKYBLUE (-5050 225);
FORCEPROP 1 LAST TOLERANCE 10%
J 2
(-5050 375);
DISPLAY 0.617021 (-5050 375);
PAINT SKYBLUE (-5050 375);
FORCEPROP 1 LAST VALUE 0.1UF
J 2
(-5050 475);
DISPLAY 0.617021 (-5050 475);
PAINT SKYBLUE (-5050 475);
FORCEPROP 1 LAST PART_NUMBER A36096-030
J 2
(-5050 275);
DISPLAY 0.617021 (-5050 275);
PAINT BLUE (-5050 275);
FORCEPROP 1 LAST LOCATION C1D21
J 2
(-5050 525);
DISPLAY 0.617021 (-5050 525);
PAINT AQUA (-5050 525);
FORCEPROP 1 LASTPIN (-5000 325) $PN 2
J 2
(-5010 305);
DISPLAY 0.617021 (-5010 305);
PAINT ORANGE (-5010 305);
FORCEPROP 1 LASTPIN (-5000 525) $PN 1
J 2
(-5010 505);
DISPLAY 0.617021 (-5010 505);
PAINT ORANGE (-5010 505);
FORCEPROP 2 LAST CDS_LIB dev_discrete
J 0
(-5000 425);
PAINT ORANGE (-5000 425);
DISPLAY INVISIBLE (-5000 425);
FORCEPROP 2 LAST SEC 1
J 0
(-5050 625);
DISPLAY 0.680851 (-5050 625);
PAINT MONO (-5050 625);
DISPLAY INVISIBLE (-5050 625);
FORCEPROP 2 LAST SEC_TYPE 0402V
J 0
(-5050 625);
DISPLAY 1.021277 (-5050 625);
PAINT ORANGE (-5050 625);
DISPLAY INVISIBLE (-5050 625);
FORCEPROP 2 LAST CDS_SEC 1
J 0
(-5050 575);
PAINT ORANGE (-5050 575);
DISPLAY INVISIBLE (-5050 575);
FORCEPROP 2 LAST CDS_LOCATION C1D21
J 2
(-5050 525);
DISPLAY 0.617021 (-5050 525);
PAINT AQUA (-5050 525);
DISPLAY INVISIBLE (-5050 525);
FORCEPROP 0 LAST ROOM HOT_SWAP
J 0
(-5050 575);
DISPLAY 1.021277 (-5050 575);
PAINT ORANGE (-5050 575);
DISPLAY INVISIBLE (-5050 575);
FORCEPROP 1 LAST PATH I121
J 2
(-5050 575);
DISPLAY 0.978723 (-5050 575);
PAINT WHITE (-5050 575);
DISPLAY INVISIBLE (-5050 575);
FORCEADD AGND0..1
(-5000 100);
FORCEPROP 3 LASTPIN (-5000 150) SIG_NAME AGND_HSC\g
J 0
(-4990 160);
DISPLAY 0.659574 (-4990 160);
PAINT MONO (-4990 160);
DISPLAY INVISIBLE (-4990 160);
FORCEPROP 1 LAST HDL_POWER AGND_HSC
J 1
(-5000 50);
DISPLAY 0.617021 (-5000 50);
PAINT GREEN (-5000 50);
FORCEPROP 2 LAST ROOM VR_P3V3
J 0
(-5025 75);
PAINT ORANGE (-5025 75);
DISPLAY INVISIBLE (-5025 75);
FORCEPROP 1 LAST PATH I122
J 0
(-4925 100);
DISPLAY 0.872340 (-4925 100);
PAINT AQUA (-4925 100);
DISPLAY INVISIBLE (-4925 100);
FORCEPROP 1 LAST BODY_TYPE PLUMBING
J 0
(-5045 57);
DISPLAY 0.340426 (-5045 57);
PAINT GREEN (-5045 57);
DISPLAY INVISIBLE (-5045 57);
FORCEPROP 2 LAST BOM_COST MIO_VRD_MAIN
J 0
(-4975 75);
PAINT ORANGE (-4975 75);
DISPLAY INVISIBLE (-4975 75);
FORCEPROP 2 LAST CDS_LIB mstr_symbols
J 0
(-5000 100);
PAINT ORANGE (-5000 100);
DISPLAY INVISIBLE (-5000 100);
FORCEPROP 1 LAST VOLTAGE 0
J 0
(-5000 100);
PAINT SKYBLUE (-5000 100);
DISPLAY INVISIBLE (-5000 100);
FORCEADD CONN3_C95678002..1
(-7750 250);
FORCEPROP 1 LAST MATERIAL CONN
J 0
(-7800 400);
DISPLAY 0.617021 (-7800 400);
PAINT SKYBLUE (-7800 400);
FORCEPROP 1 LAST LOCATION J1B3
J 0
(-7800 475);
DISPLAY 0.617021 (-7800 475);
PAINT AQUA (-7800 475);
FORCEPROP 1 LAST PART_NUMBER C95678-002
J 0
(-7800 75);
DISPLAY 0.617021 (-7800 75);
PAINT BLUE (-7800 75);
FORCEPROP 2 LASTPIN (-7650 200) $PN 3
J 0
(-7640 210);
DISPLAY 0.617021 (-7640 210);
PAINT ORANGE (-7640 210);
FORCEPROP 2 LASTPIN (-7650 300) $PN 1
J 0
(-7640 310);
DISPLAY 0.617021 (-7640 310);
PAINT ORANGE (-7640 310);
FORCEPROP 2 LASTPIN (-7650 250) $PN 2
J 0
(-7640 260);
DISPLAY 0.617021 (-7640 260);
PAINT ORANGE (-7640 260);
FORCEPROP 2 LAST CDS_LIB mstr_conn
J 0
(-7750 250);
PAINT ORANGE (-7750 250);
DISPLAY INVISIBLE (-7750 250);
FORCEPROP 2 LAST CDS_LOCATION J1B3
J 0
(-7800 475);
DISPLAY 0.617021 (-7800 475);
PAINT AQUA (-7800 475);
DISPLAY INVISIBLE (-7800 475);
FORCEPROP 2 LAST ROOM SMBUS
J 0
(-7800 500);
DISPLAY 1.021277 (-7800 500);
PAINT ORANGE (-7800 500);
DISPLAY INVISIBLE (-7800 500);
FORCEPROP 1 LAST PACK_TYPE PIP
J 0
(-7800 500);
DISPLAY 0.978723 (-7800 500);
PAINT SKYBLUE (-7800 500);
DISPLAY INVISIBLE (-7800 500);
FORCEPROP 2 LAST SEC 1
J 0
(-7800 525);
DISPLAY 0.680851 (-7800 525);
PAINT MONO (-7800 525);
DISPLAY INVISIBLE (-7800 525);
FORCEPROP 2 LAST SEC_TYPE PIP
J 0
(-7800 525);
DISPLAY 1.021277 (-7800 525);
PAINT ORANGE (-7800 525);
DISPLAY INVISIBLE (-7800 525);
FORCEPROP 2 LAST BOM_COST SM_CONTROLLER
J 0
(-7800 550);
DISPLAY 1.021277 (-7800 550);
PAINT ORANGE (-7800 550);
DISPLAY INVISIBLE (-7800 550);
FORCEPROP 1 LAST PATH I123
J 0
(-7350 400);
DISPLAY 0.978723 (-7350 400);
PAINT BLUE (-7350 400);
DISPLAY INVISIBLE (-7350 400);
FORCEADD SCONN3_D53458001..2
(-7750 675);
FORCEPROP 1 LAST LOCATION J1B4
J 0
(-7800 900);
DISPLAY 0.617021 (-7800 900);
PAINT AQUA (-7800 900);
FORCEPROP 1 LAST PART_NUMBER D53458-001
J 0
(-7800 525);
DISPLAY 0.617021 (-7800 525);
PAINT BLUE (-7800 525);
FORCEPROP 1 LAST MATERIAL EMPTY
J 0
(-7800 850);
DISPLAY 0.617021 (-7800 850);
PAINT RED (-7800 850);
FORCEPROP 2 LASTPIN (-7650 625) $PN 3
J 0
(-7640 635);
DISPLAY 0.617021 (-7640 635);
PAINT ORANGE (-7640 635);
FORCEPROP 2 LASTPIN (-7650 725) $PN 1
J 0
(-7640 735);
DISPLAY 0.617021 (-7640 735);
PAINT ORANGE (-7640 735);
FORCEPROP 2 LASTPIN (-7650 675) $PN 2
J 0
(-7640 685);
DISPLAY 0.617021 (-7640 685);
PAINT ORANGE (-7640 685);
FORCEPROP 2 LAST CDS_LIB mstr_sconn
J 0
(-7750 675);
PAINT ORANGE (-7750 675);
DISPLAY INVISIBLE (-7750 675);
FORCEPROP 1 LAST PACK_TYPE SM
J 0
(-7800 950);
DISPLAY 0.978723 (-7800 950);
PAINT SKYBLUE (-7800 950);
DISPLAY INVISIBLE (-7800 950);
FORCEPROP 2 LAST SEC_TYPE SM
J 0
(-7800 950);
DISPLAY 1.021277 (-7800 950);
PAINT ORANGE (-7800 950);
DISPLAY INVISIBLE (-7800 950);
FORCEPROP 2 LAST SEC 1
J 0
(-7800 950);
DISPLAY 0.680851 (-7800 950);
PAINT MONO (-7800 950);
DISPLAY INVISIBLE (-7800 950);
FORCEPROP 1 LAST PATH I124
J 0
(-7600 850);
DISPLAY 0.978723 (-7600 850);
PAINT WHITE (-7600 850);
DISPLAY INVISIBLE (-7600 850);
FORCEADD OFFPAGE..2
(-825 3275);
FORCEPROP 2 LAST $XR0 181 
J 0
(-636 3275);
DISPLAY 0.638298 (-636 3275);
PAINT MONO (-636 3275);
FORCEPROP 2 LAST $XR1 199 
J 0
(-516 3275);
DISPLAY 0.638298 (-516 3275);
PAINT MONO (-516 3275);
FORCEPROP 1 LAST COMMENT_BODY TRUE
J 0
(-870 3180);
DISPLAY 0.872340 (-870 3180);
PAINT GREEN (-870 3180);
DISPLAY INVISIBLE (-870 3180);
FORCEPROP 2 LAST CDS_LIB mstr_standard
J 0
(-825 3275);
PAINT ORANGE (-825 3275);
DISPLAY INVISIBLE (-825 3275);
FORCEPROP 2 LAST PATH I125
J 0
(-650 3350);
DISPLAY 1.021277 (-650 3350);
PAINT ORANGE (-650 3350);
DISPLAY INVISIBLE (-650 3350);
FORCEPROP 1 LAST OFFPAGE TRUE
J 0
(-500 3150);
DISPLAY 0.872340 (-500 3150);
PAINT GREEN (-500 3150);
DISPLAY INVISIBLE (-500 3150);
FORCEADD OFFPAGE..4
R 2
(-2625 3950);
FORCEPROP 2 LAST $XR0 181 
J 0
(-2877 3950);
DISPLAY 0.638298 (-2877 3950);
PAINT MONO (-2877 3950);
FORCEPROP 2 LAST $XR1 199 
J 0
(-2997 3950);
DISPLAY 0.638298 (-2997 3950);
PAINT MONO (-2997 3950);
FORCEPROP 1 LAST OFFPAGE TRUE
J 2
(-2950 3825);
PAINT GREEN (-2950 3825);
DISPLAY INVISIBLE (-2950 3825);
FORCEPROP 2 LAST PATH I126
J 0
(-2575 4025);
DISPLAY 1.021277 (-2575 4025);
PAINT ORANGE (-2575 4025);
DISPLAY INVISIBLE (-2575 4025);
FORCEPROP 1 LAST COMMENT_BODY TRUE
J 2
(-2600 3850);
DISPLAY 1.872340 (-2600 3850);
PAINT GREEN (-2600 3850);
DISPLAY INVISIBLE (-2600 3850);
FORCEPROP 2 LAST CDS_LIB mstr_standard
J 0
(-2625 3950);
PAINT ORANGE (-2625 3950);
DISPLAY INVISIBLE (-2625 3950);
FORCEADD RES..2
(-6500 3600);
FORCEPROP 1 LASTPIN (-6500 3500) $PN 2
J 0
(-6495 3510);
DISPLAY 0.617021 (-6495 3510);
PAINT ORANGE (-6495 3510);
FORCEPROP 1 LAST PART_NUMBER G21796-220
J 0
(-6460 3475);
DISPLAY 0.617021 (-6460 3475);
PAINT BLUE (-6460 3475);
FORCEPROP 1 LAST PACK_TYPE 0402
J 0
(-6460 3425);
DISPLAY 0.617021 (-6460 3425);
PAINT SKYBLUE (-6460 3425);
FORCEPROP 1 LAST MATERIAL CHIP
J 0
(-6460 3525);
DISPLAY 0.617021 (-6460 3525);
PAINT SKYBLUE (-6460 3525);
FORCEPROP 1 LAST WATTAGE 1/16W
J 0
(-6460 3575);
DISPLAY 0.617021 (-6460 3575);
PAINT SKYBLUE (-6460 3575);
FORCEPROP 1 LASTPIN (-6500 3700) $PN 1
J 0
(-6495 3662);
DISPLAY 0.617021 (-6495 3662);
PAINT ORANGE (-6495 3662);
FORCEPROP 1 LAST TOLERANCE 1%
J 0
(-6455 3625);
DISPLAY 0.617021 (-6455 3625);
PAINT SKYBLUE (-6455 3625);
FORCEPROP 1 LAST VALUE 11K
J 0
(-6455 3675);
DISPLAY 0.617021 (-6455 3675);
PAINT SKYBLUE (-6455 3675);
FORCEPROP 1 LAST LOCATION R1D42
J 0
(-6455 3725);
DISPLAY 0.617021 (-6455 3725);
PAINT AQUA (-6455 3725);
FORCEPROP 2 LAST CDS_LIB mstr_discrete
J 0
(-6500 3600);
PAINT ORANGE (-6500 3600);
DISPLAY INVISIBLE (-6500 3600);
FORCEPROP 0 LAST ROOM HOT_SWAP
J 0
(-6450 3775);
DISPLAY 1.021277 (-6450 3775);
PAINT ORANGE (-6450 3775);
DISPLAY INVISIBLE (-6450 3775);
FORCEPROP 1 LAST PATH I13
J 0
(-6450 3775);
DISPLAY 0.978723 (-6450 3775);
PAINT WHITE (-6450 3775);
DISPLAY INVISIBLE (-6450 3775);
FORCEPROP 2 LAST CDS_LOCATION R1D42
J 0
(-6455 3725);
DISPLAY 0.617021 (-6455 3725);
PAINT AQUA (-6455 3725);
DISPLAY INVISIBLE (-6455 3725);
FORCEPROP 2 LAST SEC 1
J 0
(-6450 3825);
DISPLAY 0.680851 (-6450 3825);
PAINT MONO (-6450 3825);
DISPLAY INVISIBLE (-6450 3825);
FORCEPROP 2 LAST SEC_TYPE 0402
J 0
(-6450 3825);
DISPLAY 1.021277 (-6450 3825);
PAINT ORANGE (-6450 3825);
DISPLAY INVISIBLE (-6450 3825);
FORCEADD RES..2
(-6600 1450);
FORCEPROP 1 LAST PACK_TYPE 0402
J 0
(-6560 1275);
DISPLAY 0.617021 (-6560 1275);
PAINT SKYBLUE (-6560 1275);
FORCEPROP 1 LASTPIN (-6600 1350) $PN 2
J 0
(-6595 1360);
DISPLAY 0.617021 (-6595 1360);
PAINT ORANGE (-6595 1360);
FORCEPROP 1 LAST WATTAGE 1/16W
J 0
(-6560 1425);
DISPLAY 0.617021 (-6560 1425);
PAINT SKYBLUE (-6560 1425);
FORCEPROP 1 LAST TOLERANCE 1%
J 0
(-6555 1475);
DISPLAY 0.617021 (-6555 1475);
PAINT SKYBLUE (-6555 1475);
FORCEPROP 1 LAST MATERIAL CHIP
J 0
(-6560 1375);
DISPLAY 0.617021 (-6560 1375);
PAINT SKYBLUE (-6560 1375);
FORCEPROP 1 LAST PART_NUMBER G21796-010
J 0
(-6560 1325);
DISPLAY 0.617021 (-6560 1325);
PAINT BLUE (-6560 1325);
FORCEPROP 1 LASTPIN (-6600 1550) $PN 1
J 0
(-6595 1512);
DISPLAY 0.617021 (-6595 1512);
PAINT ORANGE (-6595 1512);
FORCEPROP 1 LAST VALUE 100.0K
J 0
(-6555 1525);
DISPLAY 0.617021 (-6555 1525);
PAINT SKYBLUE (-6555 1525);
FORCEPROP 1 LAST LOCATION R1D37
J 0
(-6555 1575);
DISPLAY 0.617021 (-6555 1575);
PAINT AQUA (-6555 1575);
FORCEPROP 2 LAST CDS_LIB mstr_discrete
J 0
(-6600 1450);
PAINT ORANGE (-6600 1450);
DISPLAY INVISIBLE (-6600 1450);
FORCEPROP 0 LAST ROOM HOT_SWAP
J 0
(-6550 1625);
DISPLAY 1.021277 (-6550 1625);
PAINT ORANGE (-6550 1625);
DISPLAY INVISIBLE (-6550 1625);
FORCEPROP 1 LAST PATH I15
J 0
(-6550 1625);
DISPLAY 0.978723 (-6550 1625);
PAINT WHITE (-6550 1625);
DISPLAY INVISIBLE (-6550 1625);
FORCEPROP 0 LAST NO_XNET_CONNECTION 1
J 0
(-6550 1675);
PAINT MONO (-6550 1675);
DISPLAY INVISIBLE (-6550 1675);
FORCEPROP 2 LAST CDS_LOCATION R1D37
J 0
(-6555 1575);
DISPLAY 0.617021 (-6555 1575);
PAINT AQUA (-6555 1575);
DISPLAY INVISIBLE (-6555 1575);
FORCEPROP 2 LAST SEC 1
J 0
(-6550 1675);
DISPLAY 0.680851 (-6550 1675);
PAINT MONO (-6550 1675);
DISPLAY INVISIBLE (-6550 1675);
FORCEPROP 2 LAST SEC_TYPE 0402
J 0
(-6550 1675);
DISPLAY 1.021277 (-6550 1675);
PAINT ORANGE (-6550 1675);
DISPLAY INVISIBLE (-6550 1675);
FORCEADD RES..2
(-5300 1425);
FORCEPROP 1 LAST PACK_TYPE 0402
J 0
(-5260 1250);
DISPLAY 0.617021 (-5260 1250);
PAINT SKYBLUE (-5260 1250);
FORCEPROP 1 LASTPIN (-5300 1325) $PN 2
J 0
(-5295 1335);
DISPLAY 0.617021 (-5295 1335);
PAINT ORANGE (-5295 1335);
FORCEPROP 1 LASTPIN (-5300 1525) $PN 1
J 0
(-5295 1487);
DISPLAY 0.617021 (-5295 1487);
PAINT ORANGE (-5295 1487);
FORCEPROP 1 LAST TOLERANCE 1%
J 0
(-5255 1450);
DISPLAY 0.617021 (-5255 1450);
PAINT SKYBLUE (-5255 1450);
FORCEPROP 1 LAST MATERIAL CHIP
J 0
(-5260 1350);
DISPLAY 0.617021 (-5260 1350);
PAINT SKYBLUE (-5260 1350);
FORCEPROP 1 LAST WATTAGE 1/16W
J 0
(-5260 1400);
DISPLAY 0.617021 (-5260 1400);
PAINT SKYBLUE (-5260 1400);
FORCEPROP 1 LAST VALUE 100.0K
J 0
(-5255 1500);
DISPLAY 0.617021 (-5255 1500);
PAINT SKYBLUE (-5255 1500);
FORCEPROP 1 LAST PART_NUMBER G21796-010
J 0
(-5260 1300);
DISPLAY 0.617021 (-5260 1300);
PAINT BLUE (-5260 1300);
FORCEPROP 1 LAST LOCATION R1D39
J 0
(-5255 1550);
DISPLAY 0.617021 (-5255 1550);
PAINT AQUA (-5255 1550);
FORCEPROP 2 LAST CDS_LIB mstr_discrete
J 0
(-5300 1425);
PAINT ORANGE (-5300 1425);
DISPLAY INVISIBLE (-5300 1425);
FORCEPROP 2 LAST SEC_TYPE 0402
J 0
(-5250 1650);
DISPLAY 1.021277 (-5250 1650);
PAINT ORANGE (-5250 1650);
DISPLAY INVISIBLE (-5250 1650);
FORCEPROP 2 LAST SEC 1
J 0
(-5250 1650);
DISPLAY 0.680851 (-5250 1650);
PAINT MONO (-5250 1650);
DISPLAY INVISIBLE (-5250 1650);
FORCEPROP 2 LAST CDS_LOCATION R1D39
J 0
(-5255 1550);
DISPLAY 0.617021 (-5255 1550);
PAINT AQUA (-5255 1550);
DISPLAY INVISIBLE (-5255 1550);
FORCEPROP 0 LAST NO_XNET_CONNECTION 1
J 0
(-5250 1650);
PAINT MONO (-5250 1650);
DISPLAY INVISIBLE (-5250 1650);
FORCEPROP 1 LAST PATH I16
J 0
(-5250 1600);
DISPLAY 0.978723 (-5250 1600);
PAINT WHITE (-5250 1600);
DISPLAY INVISIBLE (-5250 1600);
FORCEPROP 0 LAST ROOM HOT_SWAP
J 0
(-5250 1600);
DISPLAY 1.021277 (-5250 1600);
PAINT ORANGE (-5250 1600);
DISPLAY INVISIBLE (-5250 1600);
FORCEADD RES..2
(-5600 1400);
FORCEPROP 1 LAST PACK_TYPE 0402
J 0
(-5560 1225);
DISPLAY 0.617021 (-5560 1225);
PAINT SKYBLUE (-5560 1225);
FORCEPROP 1 LASTPIN (-5600 1300) $PN 2
J 0
(-5595 1310);
DISPLAY 0.617021 (-5595 1310);
PAINT ORANGE (-5595 1310);
FORCEPROP 1 LASTPIN (-5600 1500) $PN 1
J 0
(-5595 1462);
DISPLAY 0.617021 (-5595 1462);
PAINT ORANGE (-5595 1462);
FORCEPROP 1 LAST VALUE 100.0K
J 0
(-5555 1475);
DISPLAY 0.617021 (-5555 1475);
PAINT SKYBLUE (-5555 1475);
FORCEPROP 1 LAST TOLERANCE 1%
J 0
(-5555 1425);
DISPLAY 0.617021 (-5555 1425);
PAINT SKYBLUE (-5555 1425);
FORCEPROP 1 LAST MATERIAL CHIP
J 0
(-5560 1325);
DISPLAY 0.617021 (-5560 1325);
PAINT SKYBLUE (-5560 1325);
FORCEPROP 1 LAST WATTAGE 1/16W
J 0
(-5560 1375);
DISPLAY 0.617021 (-5560 1375);
PAINT SKYBLUE (-5560 1375);
FORCEPROP 1 LAST PART_NUMBER G21796-010
J 0
(-5560 1275);
DISPLAY 0.617021 (-5560 1275);
PAINT BLUE (-5560 1275);
FORCEPROP 1 LAST LOCATION R1D32
J 0
(-5555 1525);
DISPLAY 0.617021 (-5555 1525);
PAINT AQUA (-5555 1525);
FORCEPROP 2 LAST CDS_LIB mstr_discrete
J 0
(-5600 1400);
PAINT ORANGE (-5600 1400);
DISPLAY INVISIBLE (-5600 1400);
FORCEPROP 2 LAST CDS_LOCATION R1D32
J 0
(-5555 1525);
DISPLAY 0.617021 (-5555 1525);
PAINT AQUA (-5555 1525);
DISPLAY INVISIBLE (-5555 1525);
FORCEPROP 0 LAST ROOM HOT_SWAP
J 0
(-5550 1575);
DISPLAY 1.021277 (-5550 1575);
PAINT ORANGE (-5550 1575);
DISPLAY INVISIBLE (-5550 1575);
FORCEPROP 1 LAST PATH I17
J 0
(-5550 1575);
DISPLAY 0.978723 (-5550 1575);
PAINT WHITE (-5550 1575);
DISPLAY INVISIBLE (-5550 1575);
FORCEPROP 0 LAST NO_XNET_CONNECTION 1
J 0
(-5550 1625);
PAINT MONO (-5550 1625);
DISPLAY INVISIBLE (-5550 1625);
FORCEPROP 2 LAST SEC 1
J 0
(-5550 1625);
DISPLAY 0.680851 (-5550 1625);
PAINT MONO (-5550 1625);
DISPLAY INVISIBLE (-5550 1625);
FORCEPROP 2 LAST SEC_TYPE 0402
J 0
(-5550 1625);
DISPLAY 1.021277 (-5550 1625);
PAINT ORANGE (-5550 1625);
DISPLAY INVISIBLE (-5550 1625);
FORCEADD AGND0..1
(-2750 150);
FORCEPROP 3 LASTPIN (-2750 200) SIG_NAME AGND_HSC\g
J 0
(-2740 210);
DISPLAY 0.659574 (-2740 210);
PAINT MONO (-2740 210);
DISPLAY INVISIBLE (-2740 210);
FORCEPROP 1 LAST HDL_POWER AGND_HSC
J 1
(-2750 100);
DISPLAY 0.617021 (-2750 100);
PAINT GREEN (-2750 100);
FORCEPROP 1 LAST VOLTAGE 0
J 0
(-2750 150);
PAINT SKYBLUE (-2750 150);
DISPLAY INVISIBLE (-2750 150);
FORCEPROP 2 LAST CDS_LIB mstr_symbols
J 0
(-2750 150);
PAINT ORANGE (-2750 150);
DISPLAY INVISIBLE (-2750 150);
FORCEPROP 2 LAST BOM_COST MIO_VRD_MAIN
J 0
(-2725 125);
PAINT ORANGE (-2725 125);
DISPLAY INVISIBLE (-2725 125);
FORCEPROP 1 LAST BODY_TYPE PLUMBING
J 0
(-2795 107);
DISPLAY 0.340426 (-2795 107);
PAINT GREEN (-2795 107);
DISPLAY INVISIBLE (-2795 107);
FORCEPROP 1 LAST PATH I18
J 0
(-2675 150);
DISPLAY 0.872340 (-2675 150);
PAINT AQUA (-2675 150);
DISPLAY INVISIBLE (-2675 150);
FORCEPROP 2 LAST ROOM VR_P3V3
J 0
(-2775 125);
PAINT ORANGE (-2775 125);
DISPLAY INVISIBLE (-2775 125);
FORCEADD RES..1
(-3025 300);
FORCEPROP 1 LASTPIN (-3125 300) $PN 1
J 0
(-3113 312);
DISPLAY 0.617021 (-3113 312);
PAINT ORANGE (-3113 312);
FORCEPROP 1 LAST WATTAGE 1/8W
J 2
(-3050 150);
DISPLAY 0.617021 (-3050 150);
PAINT SKYBLUE (-3050 150);
FORCEPROP 1 LAST PACK_TYPE 0805
J 0
(-3100 100);
DISPLAY 0.617021 (-3100 100);
PAINT SKYBLUE (-3100 100);
FORCEPROP 1 LAST VALUE 0.0
J 2
(-3050 200);
DISPLAY 0.617021 (-3050 200);
PAINT SKYBLUE (-3050 200);
FORCEPROP 1 LAST PART_NUMBER G22179-004
J 0
(-3075 400);
DISPLAY 0.617021 (-3075 400);
PAINT BLUE (-3075 400);
FORCEPROP 1 LAST LOCATION R1D41
J 0
(-3075 350);
DISPLAY 0.617021 (-3075 350);
PAINT AQUA (-3075 350);
FORCEPROP 1 LASTPIN (-2925 300) $PN 2
J 0
(-2963 312);
DISPLAY 0.617021 (-2963 312);
PAINT ORANGE (-2963 312);
FORCEPROP 1 LAST MATERIAL CHIP
J 0
(-3025 150);
DISPLAY 0.617021 (-3025 150);
PAINT SKYBLUE (-3025 150);
FORCEPROP 1 LAST TOLERANCE 5%
J 0
(-3025 200);
DISPLAY 0.617021 (-3025 200);
PAINT SKYBLUE (-3025 200);
FORCEPROP 2 LAST CDS_LOCATION R1D41
J 0
(-3075 350);
DISPLAY 0.617021 (-3075 350);
PAINT AQUA (-3075 350);
DISPLAY INVISIBLE (-3075 350);
FORCEPROP 1 LAST PATH I19
J 0
(-3075 450);
DISPLAY 0.978723 (-3075 450);
PAINT WHITE (-3075 450);
DISPLAY INVISIBLE (-3075 450);
FORCEPROP 0 LAST ROOM HOT_SWAP
J 0
(-3075 500);
DISPLAY 1.021277 (-3075 500);
PAINT ORANGE (-3075 500);
DISPLAY INVISIBLE (-3075 500);
FORCEPROP 2 LAST SEC 1
J 0
(-3075 500);
DISPLAY 0.680851 (-3075 500);
PAINT MONO (-3075 500);
DISPLAY INVISIBLE (-3075 500);
FORCEPROP 2 LAST SEC_TYPE 0805
J 0
(-3075 500);
DISPLAY 1.021277 (-3075 500);
PAINT ORANGE (-3075 500);
DISPLAY INVISIBLE (-3075 500);
FORCEPROP 2 LAST CDS_LIB mstr_discrete
J 0
(-3025 300);
PAINT ORANGE (-3025 300);
DISPLAY INVISIBLE (-3025 300);
FORCEADD RES..2
(-5525 4025);
FORCEPROP 1 LASTPIN (-5525 3925) $PN 2
J 0
(-5520 3935);
DISPLAY 0.617021 (-5520 3935);
PAINT ORANGE (-5520 3935);
FORCEPROP 1 LAST TOLERANCE 1%
J 0
(-5480 4050);
DISPLAY 0.617021 (-5480 4050);
PAINT SKYBLUE (-5480 4050);
FORCEPROP 1 LAST WATTAGE 1/10W
J 0
(-5485 4000);
DISPLAY 0.617021 (-5485 4000);
PAINT SKYBLUE (-5485 4000);
FORCEPROP 1 LAST MATERIAL CHIP
J 0
(-5485 3950);
DISPLAY 0.617021 (-5485 3950);
PAINT SKYBLUE (-5485 3950);
FORCEPROP 1 LAST PACK_TYPE 0603
J 0
(-5485 3850);
DISPLAY 0.617021 (-5485 3850);
PAINT SKYBLUE (-5485 3850);
FORCEPROP 1 LAST PART_NUMBER G22026-041
J 0
(-5485 3900);
DISPLAY 0.617021 (-5485 3900);
PAINT BLUE (-5485 3900);
FORCEPROP 1 LASTPIN (-5525 4125) $PN 1
J 0
(-5520 4087);
DISPLAY 0.617021 (-5520 4087);
PAINT ORANGE (-5520 4087);
FORCEPROP 1 LAST VALUE 10.0
J 0
(-5480 4100);
DISPLAY 0.617021 (-5480 4100);
PAINT SKYBLUE (-5480 4100);
FORCEPROP 1 LAST LOCATION R9P30
J 0
(-5480 4150);
DISPLAY 0.617021 (-5480 4150);
PAINT AQUA (-5480 4150);
FORCEPROP 2 LAST CDS_LIB mstr_discrete
J 0
(-5525 4025);
PAINT ORANGE (-5525 4025);
DISPLAY INVISIBLE (-5525 4025);
FORCEPROP 0 LAST ROOM HOT_SWAP
J 0
(-5475 4200);
DISPLAY 1.021277 (-5475 4200);
PAINT ORANGE (-5475 4200);
DISPLAY INVISIBLE (-5475 4200);
FORCEPROP 1 LAST PATH I2
J 0
(-5475 4200);
DISPLAY 0.978723 (-5475 4200);
PAINT WHITE (-5475 4200);
DISPLAY INVISIBLE (-5475 4200);
FORCEPROP 2 LAST CDS_LOCATION R9P30
J 0
(-5480 4150);
DISPLAY 0.617021 (-5480 4150);
PAINT AQUA (-5480 4150);
DISPLAY INVISIBLE (-5480 4150);
FORCEPROP 2 LAST SEC 1
J 0
(-5475 4250);
DISPLAY 0.680851 (-5475 4250);
PAINT MONO (-5475 4250);
DISPLAY INVISIBLE (-5475 4250);
FORCEPROP 2 LAST SEC_TYPE 0603
J 0
(-5475 4250);
DISPLAY 1.021277 (-5475 4250);
PAINT ORANGE (-5475 4250);
DISPLAY INVISIBLE (-5475 4250);
FORCEADD GND..1
(-3300 150);
FORCEPROP 3 LASTPIN (-3300 200) SIG_NAME GND\g
J 0
(-3290 210);
DISPLAY 0.659574 (-3290 210);
PAINT MONO (-3290 210);
DISPLAY INVISIBLE (-3290 210);
FORCEPROP 1 LAST BODY_TYPE PLUMBING
J 0
(-3345 107);
DISPLAY 0.340426 (-3345 107);
PAINT GREEN (-3345 107);
DISPLAY INVISIBLE (-3345 107);
FORCEPROP 1 LAST PATH I20
J 0
(-3225 150);
DISPLAY 0.872340 (-3225 150);
PAINT AQUA (-3225 150);
DISPLAY INVISIBLE (-3225 150);
FORCEPROP 1 LAST VOLTAGE 0
J 0
(-3300 150);
PAINT SKYBLUE (-3300 150);
DISPLAY INVISIBLE (-3300 150);
FORCEPROP 1 LAST SIZE 1B
J 0
(-3225 100);
DISPLAY 0.638298 (-3225 100);
PAINT GREEN (-3225 100);
DISPLAY INVISIBLE (-3225 100);
FORCEPROP 2 LAST CDS_LIB mstr_symbols
J 0
(-3300 150);
PAINT ORANGE (-3300 150);
DISPLAY INVISIBLE (-3300 150);
FORCEPROP 1 LAST HDL_POWER GND
J 0
(-3300 300);
DISPLAY 0.638298 (-3300 300);
PAINT GREEN (-3300 300);
DISPLAY INVISIBLE (-3300 300);
FORCEADD AGND0..1
(-2000 2375);
FORCEPROP 3 LASTPIN (-2000 2425) SIG_NAME AGND_HSC\g
J 0
(-1990 2435);
DISPLAY 0.659574 (-1990 2435);
PAINT MONO (-1990 2435);
DISPLAY INVISIBLE (-1990 2435);
FORCEPROP 1 LAST HDL_POWER AGND_HSC
J 1
(-2000 2325);
DISPLAY 0.617021 (-2000 2325);
PAINT GREEN (-2000 2325);
FORCEPROP 1 LAST VOLTAGE 0
J 0
(-2000 2375);
PAINT SKYBLUE (-2000 2375);
DISPLAY INVISIBLE (-2000 2375);
FORCEPROP 2 LAST BOM_COST MIO_VRD_MAIN
J 0
(-1975 2350);
PAINT ORANGE (-1975 2350);
DISPLAY INVISIBLE (-1975 2350);
FORCEPROP 2 LAST ROOM VR_P3V3
J 0
(-2025 2350);
PAINT ORANGE (-2025 2350);
DISPLAY INVISIBLE (-2025 2350);
FORCEPROP 1 LAST PATH I21
J 0
(-1925 2375);
DISPLAY 0.872340 (-1925 2375);
PAINT AQUA (-1925 2375);
DISPLAY INVISIBLE (-1925 2375);
FORCEPROP 1 LAST BODY_TYPE PLUMBING
J 0
(-2045 2332);
DISPLAY 0.340426 (-2045 2332);
PAINT GREEN (-2045 2332);
DISPLAY INVISIBLE (-2045 2332);
FORCEPROP 2 LAST CDS_LIB mstr_symbols
J 0
(-2000 2375);
PAINT ORANGE (-2000 2375);
DISPLAY INVISIBLE (-2000 2375);
FORCEADD AGND0..1
(-4725 625);
FORCEPROP 3 LASTPIN (-4725 675) SIG_NAME AGND_HSC\g
J 0
(-4715 685);
DISPLAY 0.659574 (-4715 685);
PAINT MONO (-4715 685);
DISPLAY INVISIBLE (-4715 685);
FORCEPROP 1 LAST HDL_POWER AGND_HSC
J 1
(-4725 575);
DISPLAY 0.617021 (-4725 575);
PAINT GREEN (-4725 575);
FORCEPROP 1 LAST BODY_TYPE PLUMBING
J 0
(-4770 582);
DISPLAY 0.340426 (-4770 582);
PAINT GREEN (-4770 582);
DISPLAY INVISIBLE (-4770 582);
FORCEPROP 2 LAST ROOM VR_P3V3
J 0
(-4750 600);
PAINT ORANGE (-4750 600);
DISPLAY INVISIBLE (-4750 600);
FORCEPROP 1 LAST PATH I23
J 0
(-4650 625);
DISPLAY 0.872340 (-4650 625);
PAINT AQUA (-4650 625);
DISPLAY INVISIBLE (-4650 625);
FORCEPROP 2 LAST BOM_COST MIO_VRD_MAIN
J 0
(-4700 600);
PAINT ORANGE (-4700 600);
DISPLAY INVISIBLE (-4700 600);
FORCEPROP 2 LAST CDS_LIB mstr_symbols
J 0
(-4725 625);
PAINT ORANGE (-4725 625);
DISPLAY INVISIBLE (-4725 625);
FORCEPROP 1 LAST VOLTAGE 0
J 0
(-4725 625);
PAINT SKYBLUE (-4725 625);
DISPLAY INVISIBLE (-4725 625);
FORCEADD CAP..1
(-4850 1500);
FORCEPROP 1 LASTPIN (-4850 1400) $PN 2
J 0
(-4840 1380);
DISPLAY 0.617021 (-4840 1380);
PAINT ORANGE (-4840 1380);
FORCEPROP 1 LAST MATERIAL X7R
J 0
(-4800 1400);
DISPLAY 0.617021 (-4800 1400);
PAINT SKYBLUE (-4800 1400);
FORCEPROP 1 LAST VOLTAGE 50V
J 0
(-4800 1500);
DISPLAY 0.617021 (-4800 1500);
PAINT SKYBLUE (-4800 1500);
FORCEPROP 1 LAST PACK_TYPE 0603LF
J 0
(-4800 1300);
DISPLAY 0.617021 (-4800 1300);
PAINT SKYBLUE (-4800 1300);
FORCEPROP 1 LAST TOLERANCE 10%
J 0
(-4800 1450);
DISPLAY 0.617021 (-4800 1450);
PAINT SKYBLUE (-4800 1450);
FORCEPROP 1 LASTPIN (-4850 1600) $PN 1
J 0
(-4840 1580);
DISPLAY 0.617021 (-4840 1580);
PAINT ORANGE (-4840 1580);
FORCEPROP 1 LAST LOCATION C9P14
J 0
(-4800 1600);
DISPLAY 0.617021 (-4800 1600);
PAINT AQUA (-4800 1600);
FORCEPROP 1 LAST VALUE 0.033UF
J 0
(-4800 1550);
DISPLAY 0.617021 (-4800 1550);
PAINT SKYBLUE (-4800 1550);
FORCEPROP 1 LAST PART_NUMBER 603269-064
J 0
(-4800 1350);
DISPLAY 0.617021 (-4800 1350);
PAINT BLUE (-4800 1350);
FORCEPROP 2 LAST CDS_LIB mstr_discrete
J 0
(-4850 1500);
PAINT ORANGE (-4850 1500);
DISPLAY INVISIBLE (-4850 1500);
FORCEPROP 0 LAST ROOM HOT_SWAP
J 0
(-4800 1700);
DISPLAY 1.021277 (-4800 1700);
PAINT ORANGE (-4800 1700);
DISPLAY INVISIBLE (-4800 1700);
FORCEPROP 1 LAST PATH I24
J 0
(-4800 1650);
DISPLAY 0.978723 (-4800 1650);
PAINT WHITE (-4800 1650);
DISPLAY INVISIBLE (-4800 1650);
FORCEPROP 2 LAST CDS_LOCATION C9P14
J 0
(-4800 1600);
DISPLAY 0.617021 (-4800 1600);
PAINT AQUA (-4800 1600);
DISPLAY INVISIBLE (-4800 1600);
FORCEPROP 2 LAST SEC 1
J 0
(-4800 1700);
DISPLAY 0.680851 (-4800 1700);
PAINT MONO (-4800 1700);
DISPLAY INVISIBLE (-4800 1700);
FORCEPROP 2 LAST SEC_TYPE 0603LF
J 0
(-4800 1700);
DISPLAY 1.021277 (-4800 1700);
PAINT ORANGE (-4800 1700);
DISPLAY INVISIBLE (-4800 1700);
FORCEADD RES..2
(-4625 1025);
FORCEPROP 1 LASTPIN (-4625 925) $PN 2
J 0
(-4620 935);
DISPLAY 0.617021 (-4620 935);
PAINT ORANGE (-4620 935);
FORCEPROP 1 LAST MATERIAL EMPTY
J 0
(-4585 950);
DISPLAY 0.617021 (-4585 950);
PAINT RED (-4585 950);
FORCEPROP 1 LAST PACK_TYPE 0402
J 0
(-4585 850);
DISPLAY 0.617021 (-4585 850);
PAINT SKYBLUE (-4585 850);
FORCEPROP 1 LAST PART_NUMBER G21796-017
J 0
(-4585 900);
DISPLAY 0.617021 (-4585 900);
PAINT BLUE (-4585 900);
FORCEPROP 1 LAST WATTAGE 1/16W
J 0
(-4585 1000);
DISPLAY 0.617021 (-4585 1000);
PAINT SKYBLUE (-4585 1000);
FORCEPROP 1 LASTPIN (-4625 1125) $PN 1
J 0
(-4620 1087);
DISPLAY 0.617021 (-4620 1087);
PAINT ORANGE (-4620 1087);
FORCEPROP 1 LAST TOLERANCE 1%
J 0
(-4580 1050);
DISPLAY 0.617021 (-4580 1050);
PAINT SKYBLUE (-4580 1050);
FORCEPROP 1 LAST LOCATION R1D28
J 0
(-4580 1150);
DISPLAY 0.617021 (-4580 1150);
PAINT AQUA (-4580 1150);
FORCEPROP 1 LAST VALUE 100.0
J 0
(-4580 1100);
DISPLAY 0.617021 (-4580 1100);
PAINT SKYBLUE (-4580 1100);
FORCEPROP 2 LAST CDS_LIB mstr_discrete
J 0
(-4625 1025);
PAINT ORANGE (-4625 1025);
DISPLAY INVISIBLE (-4625 1025);
FORCEPROP 2 LAST SEC 1
J 0
(-4575 1250);
DISPLAY 0.680851 (-4575 1250);
PAINT MONO (-4575 1250);
DISPLAY INVISIBLE (-4575 1250);
FORCEPROP 2 LAST CDS_LOCATION R1D28
J 0
(-4580 1150);
DISPLAY 0.617021 (-4580 1150);
PAINT AQUA (-4580 1150);
DISPLAY INVISIBLE (-4580 1150);
FORCEPROP 1 LAST PATH I26
J 0
(-4575 1200);
DISPLAY 0.978723 (-4575 1200);
PAINT WHITE (-4575 1200);
DISPLAY INVISIBLE (-4575 1200);
FORCEPROP 2 LAST SEC_TYPE 0402
J 0
(-4575 1250);
DISPLAY 1.021277 (-4575 1250);
PAINT ORANGE (-4575 1250);
DISPLAY INVISIBLE (-4575 1250);
FORCEPROP 0 LAST ROOM HOT_SWAP
J 0
(-4575 1250);
DISPLAY 1.021277 (-4575 1250);
PAINT ORANGE (-4575 1250);
DISPLAY INVISIBLE (-4575 1250);
FORCEADD RES..1
(-5600 2725);
FORCEPROP 1 LASTPIN (-5700 2725) $PN 1
J 0
(-5688 2737);
DISPLAY 0.617021 (-5688 2737);
PAINT ORANGE (-5688 2737);
FORCEPROP 1 LAST VALUE 0.0
J 2
(-5625 2625);
DISPLAY 0.617021 (-5625 2625);
PAINT SKYBLUE (-5625 2625);
FORCEPROP 1 LASTPIN (-5500 2725) $PN 2
J 0
(-5538 2737);
DISPLAY 0.617021 (-5538 2737);
PAINT ORANGE (-5538 2737);
FORCEPROP 1 LAST MATERIAL CHIP
J 0
(-5600 2625);
DISPLAY 0.617021 (-5600 2625);
PAINT SKYBLUE (-5600 2625);
FORCEPROP 1 LAST LOCATION R1D24
J 0
(-5350 2775);
DISPLAY 0.617021 (-5350 2775);
PAINT AQUA (-5350 2775);
FORCEPROP 0 LAST ROOM HOT_SWAP
J 0
(-5650 2925);
DISPLAY 1.021277 (-5650 2925);
PAINT ORANGE (-5650 2925);
DISPLAY INVISIBLE (-5650 2925);
FORCEPROP 1 LAST PATH I27
J 0
(-5650 2875);
DISPLAY 0.978723 (-5650 2875);
PAINT WHITE (-5650 2875);
DISPLAY INVISIBLE (-5650 2875);
FORCEPROP 2 LAST SEC 1
J 0
(-5650 2925);
DISPLAY 0.680851 (-5650 2925);
PAINT MONO (-5650 2925);
DISPLAY INVISIBLE (-5650 2925);
FORCEPROP 2 LAST SEC_TYPE 0402
J 0
(-5650 2925);
DISPLAY 1.021277 (-5650 2925);
PAINT ORANGE (-5650 2925);
DISPLAY INVISIBLE (-5650 2925);
FORCEPROP 1 LAST PART_NUMBER G21497-005
J 0
(-5650 2825);
DISPLAY 0.978723 (-5650 2825);
PAINT BLUE (-5650 2825);
DISPLAY INVISIBLE (-5650 2825);
FORCEPROP 1 LAST TOLERANCE 5%
J 0
(-5600 2625);
DISPLAY 0.978723 (-5600 2625);
PAINT SKYBLUE (-5600 2625);
DISPLAY INVISIBLE (-5600 2625);
FORCEPROP 1 LAST WATTAGE 1/16W
J 2
(-5625 2575);
DISPLAY 0.978723 (-5625 2575);
PAINT SKYBLUE (-5625 2575);
DISPLAY INVISIBLE (-5625 2575);
FORCEPROP 2 LAST CDS_LIB mstr_discrete
J 0
(-5600 2725);
PAINT ORANGE (-5600 2725);
DISPLAY INVISIBLE (-5600 2725);
FORCEPROP 2 LAST CDS_LOCATION R1D24
J 0
(-5350 2775);
DISPLAY 0.617021 (-5350 2775);
PAINT AQUA (-5350 2775);
DISPLAY INVISIBLE (-5350 2775);
FORCEPROP 1 LAST PACK_TYPE 0402
J 0
(-5350 2575);
DISPLAY 0.978723 (-5350 2575);
PAINT SKYBLUE (-5350 2575);
DISPLAY INVISIBLE (-5350 2575);
FORCEADD RES..1
(-5600 2675);
FORCEPROP 1 LAST PART_NUMBER G21497-005
J 0
(-6000 2625);
DISPLAY 0.617021 (-6000 2625);
PAINT BLUE (-6000 2625);
FORCEPROP 1 LASTPIN (-5700 2675) $PN 1
J 0
(-5688 2687);
DISPLAY 0.617021 (-5688 2687);
PAINT ORANGE (-5688 2687);
FORCEPROP 1 LAST WATTAGE 1/16W
J 2
(-5675 2600);
DISPLAY 0.617021 (-5675 2600);
PAINT SKYBLUE (-5675 2600);
FORCEPROP 1 LAST VALUE 0.0
J 2
(-5625 2575);
DISPLAY 0.617021 (-5625 2575);
PAINT SKYBLUE (-5625 2575);
FORCEPROP 1 LASTPIN (-5500 2675) $PN 2
J 0
(-5538 2687);
DISPLAY 0.617021 (-5538 2687);
PAINT ORANGE (-5538 2687);
FORCEPROP 1 LAST MATERIAL CHIP
J 0
(-5600 2575);
DISPLAY 0.617021 (-5600 2575);
PAINT SKYBLUE (-5600 2575);
FORCEPROP 1 LAST TOLERANCE 5%
J 0
(-5475 2600);
DISPLAY 0.617021 (-5475 2600);
PAINT SKYBLUE (-5475 2600);
FORCEPROP 1 LAST PACK_TYPE 0402
J 0
(-5400 2600);
DISPLAY 0.617021 (-5400 2600);
PAINT SKYBLUE (-5400 2600);
FORCEPROP 1 LAST LOCATION R1D25
J 0
(-5350 2725);
DISPLAY 0.617021 (-5350 2725);
PAINT AQUA (-5350 2725);
FORCEPROP 0 LAST ROOM HOT_SWAP
J 0
(-5650 2825);
DISPLAY 1.021277 (-5650 2825);
PAINT ORANGE (-5650 2825);
DISPLAY INVISIBLE (-5650 2825);
FORCEPROP 1 LAST PATH I28
J 0
(-5650 2825);
DISPLAY 0.978723 (-5650 2825);
PAINT WHITE (-5650 2825);
DISPLAY INVISIBLE (-5650 2825);
FORCEPROP 2 LAST SEC 1
J 0
(-5650 2875);
DISPLAY 0.680851 (-5650 2875);
PAINT MONO (-5650 2875);
DISPLAY INVISIBLE (-5650 2875);
FORCEPROP 2 LAST SEC_TYPE 0402
J 0
(-5650 2875);
DISPLAY 1.021277 (-5650 2875);
PAINT ORANGE (-5650 2875);
DISPLAY INVISIBLE (-5650 2875);
FORCEPROP 2 LAST CDS_LIB mstr_discrete
J 0
(-5600 2675);
PAINT ORANGE (-5600 2675);
DISPLAY INVISIBLE (-5600 2675);
FORCEPROP 2 LAST CDS_LOCATION R1D25
J 0
(-5350 2725);
DISPLAY 0.617021 (-5350 2725);
PAINT AQUA (-5350 2725);
DISPLAY INVISIBLE (-5350 2725);
FORCEADD CAP..1
(-5525 3600);
FORCEPROP 1 LASTPIN (-5525 3500) $PN 2
J 0
(-5515 3480);
DISPLAY 0.617021 (-5515 3480);
PAINT ORANGE (-5515 3480);
FORCEPROP 1 LAST TOLERANCE 10%
J 0
(-5475 3550);
DISPLAY 0.617021 (-5475 3550);
PAINT SKYBLUE (-5475 3550);
FORCEPROP 1 LAST MATERIAL X6S
J 0
(-5475 3500);
DISPLAY 0.617021 (-5475 3500);
PAINT SKYBLUE (-5475 3500);
FORCEPROP 1 LAST PART_NUMBER D97712-011
J 0
(-5475 3450);
DISPLAY 0.617021 (-5475 3450);
PAINT BLUE (-5475 3450);
FORCEPROP 1 LAST PACK_TYPE 0402
J 0
(-5475 3400);
DISPLAY 0.617021 (-5475 3400);
PAINT SKYBLUE (-5475 3400);
FORCEPROP 1 LASTPIN (-5525 3700) $PN 1
J 0
(-5515 3680);
DISPLAY 0.617021 (-5515 3680);
PAINT ORANGE (-5515 3680);
FORCEPROP 1 LAST VOLTAGE 16V
J 0
(-5475 3600);
DISPLAY 0.617021 (-5475 3600);
PAINT SKYBLUE (-5475 3600);
FORCEPROP 1 LAST VALUE 1.0UF
J 0
(-5475 3650);
DISPLAY 0.617021 (-5475 3650);
PAINT SKYBLUE (-5475 3650);
FORCEPROP 1 LAST LOCATION C1D25
J 0
(-5475 3700);
DISPLAY 0.617021 (-5475 3700);
PAINT AQUA (-5475 3700);
FORCEPROP 2 LAST CDS_LIB mstr_discrete
J 0
(-5525 3600);
PAINT MONO (-5525 3600);
DISPLAY INVISIBLE (-5525 3600);
FORCEPROP 2 LAST SEC 1
J 0
(-5475 3800);
DISPLAY 0.680851 (-5475 3800);
PAINT MONO (-5475 3800);
DISPLAY INVISIBLE (-5475 3800);
FORCEPROP 2 LAST CDS_LOCATION C1D25
J 0
(-5475 3700);
DISPLAY 0.617021 (-5475 3700);
PAINT AQUA (-5475 3700);
DISPLAY INVISIBLE (-5475 3700);
FORCEPROP 1 LAST PATH I3
J 0
(-5475 3750);
DISPLAY 0.978723 (-5475 3750);
PAINT WHITE (-5475 3750);
DISPLAY INVISIBLE (-5475 3750);
FORCEPROP 0 LAST ROOM HOT_SWAP
J 0
(-5475 3750);
DISPLAY 1.021277 (-5475 3750);
PAINT ORANGE (-5475 3750);
DISPLAY INVISIBLE (-5475 3750);
FORCEPROP 2 LAST SEC_TYPE 0402
J 0
(-5475 3800);
DISPLAY 1.021277 (-5475 3800);
PAINT ORANGE (-5475 3800);
DISPLAY INVISIBLE (-5475 3800);
FORCEADD OFFPAGE..4
R 2
(-6750 2725);
FORCEPROP 2 LAST $XR0 138 
J 0
(-7032 2725);
DISPLAY 0.638298 (-7032 2725);
PAINT MONO (-7032 2725);
FORCEPROP 2 LAST $XR1 159 
J 0
(-7152 2725);
DISPLAY 0.638298 (-7152 2725);
PAINT MONO (-7152 2725);
FORCEPROP 2 LAST $XR2 181 
J 0
(-7272 2725);
DISPLAY 0.638298 (-7272 2725);
PAINT MONO (-7272 2725);
FORCEPROP 2 LAST $XR3 247 
J 0
(-7272 2725);
DISPLAY 0.638298 (-7272 2725);
PAINT MONO (-7272 2725);
FORCEPROP 1 LAST OFFPAGE TRUE
J 2
(-7075 2600);
PAINT GREEN (-7075 2600);
DISPLAY INVISIBLE (-7075 2600);
FORCEPROP 1 LAST COMMENT_BODY TRUE
J 2
(-6725 2625);
DISPLAY 1.872340 (-6725 2625);
PAINT GREEN (-6725 2625);
DISPLAY INVISIBLE (-6725 2625);
FORCEPROP 2 LAST CDS_LIB mstr_standard
J 0
(-6750 2725);
PAINT ORANGE (-6750 2725);
DISPLAY INVISIBLE (-6750 2725);
FORCEPROP 2 LAST PATH I30
J 0
(-6700 2800);
DISPLAY 1.021277 (-6700 2800);
PAINT ORANGE (-6700 2800);
DISPLAY INVISIBLE (-6700 2800);
FORCEADD OFFPAGE..3
R 2
(-6750 2675);
FORCEPROP 2 LAST $XR0 138 
J 0
(-7030 2675);
DISPLAY 0.638298 (-7030 2675);
PAINT MONO (-7030 2675);
FORCEPROP 2 LAST $XR1 159 
J 0
(-7150 2675);
DISPLAY 0.638298 (-7150 2675);
PAINT MONO (-7150 2675);
FORCEPROP 2 LAST $XR2 181 
J 0
(-7270 2675);
DISPLAY 0.638298 (-7270 2675);
PAINT MONO (-7270 2675);
FORCEPROP 2 LAST $XR3 247 
J 0
(-7270 2675);
DISPLAY 0.638298 (-7270 2675);
PAINT MONO (-7270 2675);
FORCEPROP 1 LAST OFFPAGE TRUE
J 2
(-7075 2550);
DISPLAY 0.872340 (-7075 2550);
PAINT GREEN (-7075 2550);
DISPLAY INVISIBLE (-7075 2550);
FORCEPROP 1 LAST COMMENT_BODY TRUE
J 2
(-6700 2575);
DISPLAY 0.872340 (-6700 2575);
PAINT GREEN (-6700 2575);
DISPLAY INVISIBLE (-6700 2575);
FORCEPROP 2 LAST CDS_LIB mstr_standard
J 0
(-6750 2675);
PAINT ORANGE (-6750 2675);
DISPLAY INVISIBLE (-6750 2675);
FORCEPROP 2 LAST PATH I31
J 0
(-6700 2750);
DISPLAY 1.021277 (-6700 2750);
PAINT ORANGE (-6700 2750);
DISPLAY INVISIBLE (-6700 2750);
FORCEADD RES..2
(-8000 2375);
FORCEPROP 1 LASTPIN (-8000 2275) $PN 2
J 0
(-7995 2285);
DISPLAY 0.617021 (-7995 2285);
PAINT ORANGE (-7995 2285);
FORCEPROP 1 LASTPIN (-8000 2475) $PN 1
J 0
(-7995 2437);
DISPLAY 0.617021 (-7995 2437);
PAINT ORANGE (-7995 2437);
FORCEPROP 1 LAST WATTAGE 1/16W
J 0
(-7960 2425);
DISPLAY 0.617021 (-7960 2425);
PAINT SKYBLUE (-7960 2425);
FORCEPROP 1 LAST MATERIAL CHIP
J 0
(-7960 2375);
DISPLAY 0.617021 (-7960 2375);
PAINT SKYBLUE (-7960 2375);
FORCEPROP 1 LAST PACK_TYPE 0402
J 0
(-7960 2275);
DISPLAY 0.617021 (-7960 2275);
PAINT SKYBLUE (-7960 2275);
FORCEPROP 1 LAST TOLERANCE 1%
J 0
(-7955 2475);
DISPLAY 0.617021 (-7955 2475);
PAINT SKYBLUE (-7955 2475);
FORCEPROP 1 LAST LOCATION R9P17
J 0
(-7980 2525);
DISPLAY 0.617021 (-7980 2525);
PAINT AQUA (-7980 2525);
FORCEPROP 1 LAST PART_NUMBER G21796-109
J 0
(-7985 2325);
DISPLAY 0.617021 (-7985 2325);
PAINT BLUE (-7985 2325);
FORCEPROP 1 LAST VALUE 150.0K
J 0
(-7980 2225);
DISPLAY 0.617021 (-7980 2225);
PAINT SKYBLUE (-7980 2225);
FORCEPROP 2 LAST CDS_LOCATION R9P17
J 0
(-7980 2525);
DISPLAY 0.617021 (-7980 2525);
PAINT AQUA (-7980 2525);
DISPLAY INVISIBLE (-7980 2525);
FORCEPROP 2 LAST CDS_LIB mstr_discrete
J 0
(-8000 2375);
PAINT ORANGE (-8000 2375);
DISPLAY INVISIBLE (-8000 2375);
FORCEPROP 0 LAST ROOM HOT_SWAP
J 0
(-8050 2525);
DISPLAY 1.021277 (-8050 2525);
PAINT ORANGE (-8050 2525);
DISPLAY INVISIBLE (-8050 2525);
FORCEPROP 1 LAST PATH I33
J 0
(-7950 2550);
DISPLAY 0.978723 (-7950 2550);
PAINT WHITE (-7950 2550);
DISPLAY INVISIBLE (-7950 2550);
FORCEPROP 2 LAST SEC_TYPE 0402
J 0
(-7950 2600);
DISPLAY 1.021277 (-7950 2600);
PAINT ORANGE (-7950 2600);
DISPLAY INVISIBLE (-7950 2600);
FORCEPROP 2 LAST SEC 1
J 0
(-7950 2600);
DISPLAY 0.680851 (-7950 2600);
PAINT MONO (-7950 2600);
DISPLAY INVISIBLE (-7950 2600);
FORCEADD AGND0..1
(-7675 2075);
FORCEPROP 3 LASTPIN (-7675 2125) SIG_NAME AGND_HSC\g
J 0
(-7665 2135);
DISPLAY 0.659574 (-7665 2135);
PAINT MONO (-7665 2135);
DISPLAY INVISIBLE (-7665 2135);
FORCEPROP 1 LAST HDL_POWER AGND_HSC
J 1
(-7675 2025);
DISPLAY 0.617021 (-7675 2025);
PAINT GREEN (-7675 2025);
FORCEPROP 1 LAST BODY_TYPE PLUMBING
J 0
(-7720 2032);
DISPLAY 0.340426 (-7720 2032);
PAINT GREEN (-7720 2032);
DISPLAY INVISIBLE (-7720 2032);
FORCEPROP 2 LAST ROOM VR_P3V3
J 0
(-7700 2050);
PAINT ORANGE (-7700 2050);
DISPLAY INVISIBLE (-7700 2050);
FORCEPROP 1 LAST PATH I34
J 0
(-7600 2075);
DISPLAY 0.872340 (-7600 2075);
PAINT AQUA (-7600 2075);
DISPLAY INVISIBLE (-7600 2075);
FORCEPROP 2 LAST BOM_COST MIO_VRD_MAIN
J 0
(-7650 2050);
PAINT ORANGE (-7650 2050);
DISPLAY INVISIBLE (-7650 2050);
FORCEPROP 2 LAST CDS_LIB mstr_symbols
J 0
(-7675 2075);
PAINT ORANGE (-7675 2075);
DISPLAY INVISIBLE (-7675 2075);
FORCEPROP 1 LAST VOLTAGE 0
J 0
(-7675 2075);
PAINT SKYBLUE (-7675 2075);
DISPLAY INVISIBLE (-7675 2075);
FORCEADD RES..2
(-7675 2375);
FORCEPROP 1 LAST MATERIAL CHIP
J 0
(-7635 2275);
DISPLAY 0.617021 (-7635 2275);
PAINT SKYBLUE (-7635 2275);
FORCEPROP 1 LAST PACK_TYPE 0402
J 0
(-7635 2175);
DISPLAY 0.617021 (-7635 2175);
PAINT SKYBLUE (-7635 2175);
FORCEPROP 1 LASTPIN (-7675 2275) $PN 2
J 0
(-7670 2285);
DISPLAY 0.617021 (-7670 2285);
PAINT ORANGE (-7670 2285);
FORCEPROP 1 LAST TOLERANCE 5%
J 0
(-7630 2375);
DISPLAY 0.617021 (-7630 2375);
PAINT SKYBLUE (-7630 2375);
FORCEPROP 1 LASTPIN (-7675 2475) $PN 1
J 0
(-7670 2437);
DISPLAY 0.617021 (-7670 2437);
PAINT ORANGE (-7670 2437);
FORCEPROP 1 LAST WATTAGE 1/16W
J 0
(-7635 2325);
DISPLAY 0.617021 (-7635 2325);
PAINT SKYBLUE (-7635 2325);
FORCEPROP 1 LAST LOCATION R9P16
J 0
(-7630 2475);
DISPLAY 0.617021 (-7630 2475);
PAINT AQUA (-7630 2475);
FORCEPROP 1 LAST VALUE 0.0
J 0
(-7630 2425);
DISPLAY 0.617021 (-7630 2425);
PAINT SKYBLUE (-7630 2425);
FORCEPROP 1 LAST PART_NUMBER G21497-005
J 0
(-7635 2225);
DISPLAY 0.617021 (-7635 2225);
PAINT BLUE (-7635 2225);
FORCEPROP 0 LAST ROOM HOT_SWAP
J 0
(-7725 2525);
DISPLAY 1.021277 (-7725 2525);
PAINT ORANGE (-7725 2525);
DISPLAY INVISIBLE (-7725 2525);
FORCEPROP 2 LAST CDS_LOCATION R9P16
J 0
(-7630 2475);
DISPLAY 0.617021 (-7630 2475);
PAINT AQUA (-7630 2475);
DISPLAY INVISIBLE (-7630 2475);
FORCEPROP 2 LAST CDS_LIB mstr_discrete
J 0
(-7675 2375);
PAINT ORANGE (-7675 2375);
DISPLAY INVISIBLE (-7675 2375);
FORCEPROP 1 LAST PATH I36
J 0
(-7625 2550);
DISPLAY 0.978723 (-7625 2550);
PAINT WHITE (-7625 2550);
DISPLAY INVISIBLE (-7625 2550);
FORCEPROP 2 LAST SEC 1
J 0
(-7625 2600);
DISPLAY 0.680851 (-7625 2600);
PAINT MONO (-7625 2600);
DISPLAY INVISIBLE (-7625 2600);
FORCEPROP 2 LAST SEC_TYPE 0402
J 0
(-7625 2600);
DISPLAY 1.021277 (-7625 2600);
PAINT ORANGE (-7625 2600);
DISPLAY INVISIBLE (-7625 2600);
FORCEADD RES..2
(-8000 2825);
FORCEPROP 1 LASTPIN (-8000 2725) $PN 2
J 0
(-7995 2735);
DISPLAY 0.617021 (-7995 2735);
PAINT ORANGE (-7995 2735);
FORCEPROP 1 LASTPIN (-8000 2925) $PN 1
J 0
(-7995 2887);
DISPLAY 0.617021 (-7995 2887);
PAINT ORANGE (-7995 2887);
FORCEPROP 1 LAST PACK_TYPE 0402
J 0
(-7985 2650);
DISPLAY 0.617021 (-7985 2650);
PAINT SKYBLUE (-7985 2650);
FORCEPROP 1 LAST VALUE 4.75K
J 0
(-7955 2900);
DISPLAY 0.617021 (-7955 2900);
PAINT SKYBLUE (-7955 2900);
FORCEPROP 1 LAST PART_NUMBER G21796-072
J 0
(-7985 2700);
DISPLAY 0.617021 (-7985 2700);
PAINT BLUE (-7985 2700);
FORCEPROP 1 LAST LOCATION R1D29
J 0
(-8030 3000);
DISPLAY 0.617021 (-8030 3000);
PAINT AQUA (-8030 3000);
FORCEPROP 1 LAST MATERIAL EMPTY
J 0
(-7885 2750);
DISPLAY 0.617021 (-7885 2750);
PAINT RED (-7885 2750);
FORCEPROP 1 LAST WATTAGE 1/16W
J 0
(-7885 2800);
DISPLAY 0.617021 (-7885 2800);
PAINT SKYBLUE (-7885 2800);
FORCEPROP 1 LAST TOLERANCE 1%
J 0
(-7880 2850);
DISPLAY 0.617021 (-7880 2850);
PAINT SKYBLUE (-7880 2850);
FORCEPROP 2 LAST CDS_LIB mstr_discrete
J 0
(-8000 2825);
PAINT ORANGE (-8000 2825);
DISPLAY INVISIBLE (-8000 2825);
FORCEPROP 1 LAST PATH I37
J 0
(-7950 3000);
DISPLAY 0.978723 (-7950 3000);
PAINT WHITE (-7950 3000);
DISPLAY INVISIBLE (-7950 3000);
FORCEPROP 2 LAST CDS_LOCATION R1D29
J 0
(-8030 3000);
DISPLAY 0.617021 (-8030 3000);
PAINT AQUA (-8030 3000);
DISPLAY INVISIBLE (-8030 3000);
FORCEPROP 0 LAST ROOM HOT_SWAP
J 0
(-7950 3050);
DISPLAY 1.021277 (-7950 3050);
PAINT ORANGE (-7950 3050);
DISPLAY INVISIBLE (-7950 3050);
FORCEPROP 0 LAST NO_XNET_CONNECTION 1
J 0
(-7950 3050);
PAINT MONO (-7950 3050);
DISPLAY INVISIBLE (-7950 3050);
FORCEPROP 2 LAST SEC 1
J 0
(-7950 3050);
DISPLAY 0.680851 (-7950 3050);
PAINT MONO (-7950 3050);
DISPLAY INVISIBLE (-7950 3050);
FORCEPROP 2 LAST SEC_TYPE 0402
J 0
(-7950 3050);
DISPLAY 1.021277 (-7950 3050);
PAINT ORANGE (-7950 3050);
DISPLAY INVISIBLE (-7950 3050);
FORCEADD RES..2
(-7675 2850);
FORCEPROP 1 LASTPIN (-7675 2750) $PN 2
J 0
(-7670 2760);
DISPLAY 0.617021 (-7670 2760);
PAINT ORANGE (-7670 2760);
FORCEPROP 1 LAST PACK_TYPE 0402
J 0
(-7635 2675);
DISPLAY 0.617021 (-7635 2675);
PAINT SKYBLUE (-7635 2675);
FORCEPROP 1 LASTPIN (-7675 2950) $PN 1
J 0
(-7670 2912);
DISPLAY 0.617021 (-7670 2912);
PAINT ORANGE (-7670 2912);
FORCEPROP 1 LAST VALUE 4.75K
J 0
(-7605 2925);
DISPLAY 0.617021 (-7605 2925);
PAINT SKYBLUE (-7605 2925);
FORCEPROP 1 LAST LOCATION R1D27
J 0
(-7630 2975);
DISPLAY 0.617021 (-7630 2975);
PAINT AQUA (-7630 2975);
FORCEPROP 1 LAST TOLERANCE 1%
J 0
(-7505 2875);
DISPLAY 0.617021 (-7505 2875);
PAINT SKYBLUE (-7505 2875);
FORCEPROP 1 LAST WATTAGE 1/16W
J 0
(-7535 2825);
DISPLAY 0.617021 (-7535 2825);
PAINT SKYBLUE (-7535 2825);
FORCEPROP 1 LAST PART_NUMBER G21796-072
J 0
(-7635 2725);
DISPLAY 0.617021 (-7635 2725);
PAINT BLUE (-7635 2725);
FORCEPROP 1 LAST MATERIAL EMPTY
J 0
(-7560 2775);
DISPLAY 0.617021 (-7560 2775);
PAINT RED (-7560 2775);
FORCEPROP 2 LAST CDS_LIB mstr_discrete
J 0
(-7675 2850);
PAINT ORANGE (-7675 2850);
DISPLAY INVISIBLE (-7675 2850);
FORCEPROP 1 LAST PATH I38
J 0
(-7625 3025);
DISPLAY 0.978723 (-7625 3025);
PAINT WHITE (-7625 3025);
DISPLAY INVISIBLE (-7625 3025);
FORCEPROP 2 LAST CDS_LOCATION R1D27
J 0
(-7630 2975);
DISPLAY 0.617021 (-7630 2975);
PAINT AQUA (-7630 2975);
DISPLAY INVISIBLE (-7630 2975);
FORCEPROP 2 LAST SEC_TYPE 0402
J 0
(-7625 3075);
DISPLAY 1.021277 (-7625 3075);
PAINT ORANGE (-7625 3075);
DISPLAY INVISIBLE (-7625 3075);
FORCEPROP 2 LAST SEC 1
J 0
(-7625 3075);
DISPLAY 0.680851 (-7625 3075);
PAINT MONO (-7625 3075);
DISPLAY INVISIBLE (-7625 3075);
FORCEPROP 0 LAST NO_XNET_CONNECTION 1
J 0
(-7625 3075);
PAINT MONO (-7625 3075);
DISPLAY INVISIBLE (-7625 3075);
FORCEPROP 0 LAST ROOM HOT_SWAP
J 0
(-7625 3075);
DISPLAY 1.021277 (-7625 3075);
PAINT ORANGE (-7625 3075);
DISPLAY INVISIBLE (-7625 3075);
FORCEADD RES..2
R 2
(-3125 1075);
FORCEPROP 1 LASTPIN (-3125 975) $PN 2
J 2
(-3130 985);
DISPLAY 0.617021 (-3130 985);
PAINT ORANGE (-3130 985);
FORCEPROP 1 LAST PART_NUMBER G21796-107
J 2
(-3140 950);
DISPLAY 0.617021 (-3140 950);
PAINT BLUE (-3140 950);
FORCEPROP 1 LAST MATERIAL CHIP
J 2
(-3165 1000);
DISPLAY 0.617021 (-3165 1000);
PAINT SKYBLUE (-3165 1000);
FORCEPROP 1 LAST PACK_TYPE 0402
J 2
(-3265 1050);
DISPLAY 0.617021 (-3265 1050);
PAINT SKYBLUE (-3265 1050);
FORCEPROP 1 LAST WATTAGE 1/16W
J 2
(-3165 1050);
DISPLAY 0.617021 (-3165 1050);
PAINT SKYBLUE (-3165 1050);
FORCEPROP 1 LAST TOLERANCE 1%
J 2
(-3170 1100);
DISPLAY 0.617021 (-3170 1100);
PAINT SKYBLUE (-3170 1100);
FORCEPROP 1 LAST VALUE 15.0K
J 2
(-3170 1150);
DISPLAY 0.617021 (-3170 1150);
PAINT SKYBLUE (-3170 1150);
FORCEPROP 1 LAST LOCATION R9P18
J 2
(-3145 1200);
DISPLAY 0.617021 (-3145 1200);
PAINT AQUA (-3145 1200);
FORCEPROP 1 LASTPIN (-3125 1175) $PN 1
J 2
(-3130 1137);
DISPLAY 0.617021 (-3130 1137);
PAINT ORANGE (-3130 1137);
FORCEPROP 2 LAST CDS_LIB mstr_discrete
J 2
(-3125 1075);
PAINT ORANGE (-3125 1075);
DISPLAY INVISIBLE (-3125 1075);
FORCEPROP 2 LAST CDS_LOCATION R9P18
J 2
(-3145 1200);
DISPLAY 0.617021 (-3145 1200);
PAINT AQUA (-3145 1200);
DISPLAY INVISIBLE (-3145 1200);
FORCEPROP 2 LAST ROOM HOT_SWAP
J 2
(-3175 1250);
PAINT PEACH (-3175 1250);
DISPLAY INVISIBLE (-3175 1250);
FORCEPROP 1 LAST PATH I41
J 2
(-3175 1250);
DISPLAY 0.978723 (-3175 1250);
PAINT WHITE (-3175 1250);
DISPLAY INVISIBLE (-3175 1250);
FORCEPROP 2 LAST BOM_COST MIO_USB
J 2
(-3175 1250);
PAINT MONO (-3175 1250);
DISPLAY INVISIBLE (-3175 1250);
FORCEPROP 2 LAST SEC 1
J 0
(-3175 1300);
DISPLAY 0.680851 (-3175 1300);
PAINT MONO (-3175 1300);
DISPLAY INVISIBLE (-3175 1300);
FORCEPROP 2 LAST SEC_TYPE 0402
J 0
(-3175 1300);
DISPLAY 1.021277 (-3175 1300);
PAINT ORANGE (-3175 1300);
DISPLAY INVISIBLE (-3175 1300);
FORCEADD RES..2
R 2
(-2825 750);
FORCEPROP 1 LAST PART_NUMBER G21796-161
J 2
(-2865 625);
DISPLAY 0.617021 (-2865 625);
PAINT BLUE (-2865 625);
FORCEPROP 1 LAST LOCATION R1D31
J 2
(-2970 850);
DISPLAY 0.617021 (-2970 850);
PAINT AQUA (-2970 850);
FORCEPROP 1 LAST WATTAGE 1/16W
J 2
(-2865 725);
DISPLAY 0.617021 (-2865 725);
PAINT SKYBLUE (-2865 725);
FORCEPROP 1 LAST MATERIAL CHIP
J 2
(-2865 675);
DISPLAY 0.617021 (-2865 675);
PAINT SKYBLUE (-2865 675);
FORCEPROP 1 LAST PACK_TYPE 0402
J 2
(-2865 575);
DISPLAY 0.617021 (-2865 575);
PAINT SKYBLUE (-2865 575);
FORCEPROP 1 LASTPIN (-2825 650) $PN 2
J 2
(-2830 660);
DISPLAY 0.617021 (-2830 660);
PAINT ORANGE (-2830 660);
FORCEPROP 1 LAST VALUE 6.19K
J 2
(-2870 825);
DISPLAY 0.617021 (-2870 825);
PAINT SKYBLUE (-2870 825);
FORCEPROP 1 LAST TOLERANCE 1%
J 2
(-2870 775);
DISPLAY 0.617021 (-2870 775);
PAINT SKYBLUE (-2870 775);
FORCEPROP 1 LASTPIN (-2825 850) $PN 1
J 2
(-2830 812);
DISPLAY 0.617021 (-2830 812);
PAINT ORANGE (-2830 812);
FORCEPROP 2 LAST CDS_LIB mstr_discrete
J 2
(-2825 750);
PAINT ORANGE (-2825 750);
DISPLAY INVISIBLE (-2825 750);
FORCEPROP 2 LAST CDS_LOCATION R1D31
J 2
(-2970 850);
DISPLAY 0.617021 (-2970 850);
PAINT AQUA (-2970 850);
DISPLAY INVISIBLE (-2970 850);
FORCEPROP 2 LAST SEC_TYPE 0402
J 0
(-2875 975);
DISPLAY 1.021277 (-2875 975);
PAINT ORANGE (-2875 975);
DISPLAY INVISIBLE (-2875 975);
FORCEPROP 2 LAST SEC 1
J 0
(-2875 975);
DISPLAY 0.680851 (-2875 975);
PAINT MONO (-2875 975);
DISPLAY INVISIBLE (-2875 975);
FORCEPROP 0 LAST ROOM HOT_SWAP
J 2
(-2875 975);
DISPLAY 1.021277 (-2875 975);
PAINT ORANGE (-2875 975);
DISPLAY INVISIBLE (-2875 975);
FORCEPROP 1 LAST PATH I43
J 2
(-2875 925);
DISPLAY 0.978723 (-2875 925);
PAINT WHITE (-2875 925);
DISPLAY INVISIBLE (-2875 925);
FORCEADD GND..1
(-2825 550);
FORCEPROP 3 LASTPIN (-2825 600) SIG_NAME GND\g
J 0
(-2815 610);
DISPLAY 0.659574 (-2815 610);
PAINT MONO (-2815 610);
DISPLAY INVISIBLE (-2815 610);
FORCEPROP 1 LAST BODY_TYPE PLUMBING
J 0
(-2870 507);
DISPLAY 0.340426 (-2870 507);
PAINT GREEN (-2870 507);
DISPLAY INVISIBLE (-2870 507);
FORCEPROP 1 LAST SIZE 1B
J 0
(-2750 500);
DISPLAY 0.638298 (-2750 500);
PAINT GREEN (-2750 500);
DISPLAY INVISIBLE (-2750 500);
FORCEPROP 1 LAST HDL_POWER GND
J 0
(-2825 700);
DISPLAY 0.638298 (-2825 700);
PAINT GREEN (-2825 700);
DISPLAY INVISIBLE (-2825 700);
FORCEPROP 2 LAST CDS_LIB mstr_symbols
J 0
(-2825 550);
PAINT ORANGE (-2825 550);
DISPLAY INVISIBLE (-2825 550);
FORCEPROP 1 LAST VOLTAGE 0
J 0
(-2825 550);
PAINT SKYBLUE (-2825 550);
DISPLAY INVISIBLE (-2825 550);
FORCEPROP 1 LAST PATH I44
J 0
(-2750 550);
DISPLAY 0.872340 (-2750 550);
PAINT AQUA (-2750 550);
DISPLAY INVISIBLE (-2750 550);
FORCEADD OFFPAGE..2
(-750 925);
FORCEPROP 2 LAST $XR0 196 
J 0
(-561 925);
DISPLAY 0.638298 (-561 925);
PAINT MONO (-561 925);
FORCEPROP 1 LAST COMMENT_BODY TRUE
J 0
(-795 830);
DISPLAY 0.872340 (-795 830);
PAINT GREEN (-795 830);
DISPLAY INVISIBLE (-795 830);
FORCEPROP 2 LAST CDS_LIB mstr_standard
J 0
(-750 925);
PAINT ORANGE (-750 925);
DISPLAY INVISIBLE (-750 925);
FORCEPROP 1 LAST OFFPAGE TRUE
J 0
(-425 800);
DISPLAY 0.872340 (-425 800);
PAINT GREEN (-425 800);
DISPLAY INVISIBLE (-425 800);
FORCEPROP 2 LAST PATH I45
J 0
(-575 1000);
DISPLAY 1.021277 (-575 1000);
PAINT ORANGE (-575 1000);
DISPLAY INVISIBLE (-575 1000);
FORCEADD OFFPAGE..2
(-750 1375);
FORCEPROP 2 LAST $XR0 133 
J 0
(-561 1375);
DISPLAY 0.638298 (-561 1375);
PAINT MONO (-561 1375);
FORCEPROP 2 LAST $XR1 119 
J 0
(-441 1375);
DISPLAY 0.638298 (-441 1375);
PAINT MONO (-441 1375);
FORCEPROP 2 LAST $XR2 144 
J 0
(-321 1375);
DISPLAY 0.638298 (-321 1375);
PAINT MONO (-321 1375);
FORCEPROP 1 LAST COMMENT_BODY TRUE
J 0
(-795 1280);
DISPLAY 0.872340 (-795 1280);
PAINT GREEN (-795 1280);
DISPLAY INVISIBLE (-795 1280);
FORCEPROP 2 LAST CDS_LIB mstr_standard
J 0
(-750 1375);
PAINT ORANGE (-750 1375);
DISPLAY INVISIBLE (-750 1375);
FORCEPROP 2 LAST PATH I49
J 0
(-575 1450);
DISPLAY 1.021277 (-575 1450);
PAINT ORANGE (-575 1450);
DISPLAY INVISIBLE (-575 1450);
FORCEPROP 1 LAST OFFPAGE TRUE
J 0
(-425 1250);
DISPLAY 0.872340 (-425 1250);
PAINT GREEN (-425 1250);
DISPLAY INVISIBLE (-425 1250);
FORCEADD OFFPAGE..4
R 2
(-7225 2450);
FORCEPROP 2 LAST $XR0 181 
J 0
(-7477 2450);
DISPLAY 0.638298 (-7477 2450);
PAINT MONO (-7477 2450);
FORCEPROP 1 LAST OFFPAGE TRUE
J 2
(-7550 2325);
PAINT GREEN (-7550 2325);
DISPLAY INVISIBLE (-7550 2325);
FORCEPROP 1 LAST COMMENT_BODY TRUE
J 2
(-7200 2350);
DISPLAY 1.872340 (-7200 2350);
PAINT GREEN (-7200 2350);
DISPLAY INVISIBLE (-7200 2350);
FORCEPROP 2 LAST CDS_LIB mstr_standard
J 0
(-7225 2450);
PAINT ORANGE (-7225 2450);
DISPLAY INVISIBLE (-7225 2450);
FORCEPROP 2 LAST PATH I50
J 0
(-7175 2525);
DISPLAY 1.021277 (-7175 2525);
PAINT ORANGE (-7175 2525);
DISPLAY INVISIBLE (-7175 2525);
FORCEADD AGND0..1
(-7025 1975);
FORCEPROP 3 LASTPIN (-7025 2025) SIG_NAME AGND_HSC\g
J 0
(-7015 2035);
DISPLAY 0.659574 (-7015 2035);
PAINT MONO (-7015 2035);
DISPLAY INVISIBLE (-7015 2035);
FORCEPROP 1 LAST HDL_POWER AGND_HSC
J 1
(-7025 1925);
DISPLAY 0.617021 (-7025 1925);
PAINT GREEN (-7025 1925);
FORCEPROP 2 LAST ROOM VR_P3V3
J 0
(-7050 1950);
PAINT ORANGE (-7050 1950);
DISPLAY INVISIBLE (-7050 1950);
FORCEPROP 1 LAST PATH I52
J 0
(-6950 1975);
DISPLAY 0.872340 (-6950 1975);
PAINT AQUA (-6950 1975);
DISPLAY INVISIBLE (-6950 1975);
FORCEPROP 1 LAST BODY_TYPE PLUMBING
J 0
(-7070 1932);
DISPLAY 0.340426 (-7070 1932);
PAINT GREEN (-7070 1932);
DISPLAY INVISIBLE (-7070 1932);
FORCEPROP 2 LAST CDS_LIB mstr_symbols
J 0
(-7025 1975);
PAINT ORANGE (-7025 1975);
DISPLAY INVISIBLE (-7025 1975);
FORCEPROP 2 LAST BOM_COST MIO_VRD_MAIN
J 0
(-7000 1950);
PAINT ORANGE (-7000 1950);
DISPLAY INVISIBLE (-7000 1950);
FORCEPROP 1 LAST VOLTAGE 0
J 0
(-7025 1975);
PAINT SKYBLUE (-7025 1975);
DISPLAY INVISIBLE (-7025 1975);
FORCEADD CAP_A..1
R 2
(-7025 2175);
FORCEPROP 1 LAST PACK_TYPE 0402V
J 2
(-7075 1975);
DISPLAY 0.617021 (-7075 1975);
PAINT SKYBLUE (-7075 1975);
FORCEPROP 1 LAST PART_NUMBER A36096-030
J 2
(-7075 2025);
DISPLAY 0.617021 (-7075 2025);
PAINT BLUE (-7075 2025);
FORCEPROP 1 LAST VALUE 0.1UF
J 2
(-7075 2225);
DISPLAY 0.617021 (-7075 2225);
PAINT SKYBLUE (-7075 2225);
FORCEPROP 1 LAST LOCATION C1D11
J 2
(-7075 2275);
DISPLAY 0.617021 (-7075 2275);
PAINT AQUA (-7075 2275);
FORCEPROP 1 LAST TOLERANCE 10%
J 2
(-7075 2125);
DISPLAY 0.617021 (-7075 2125);
PAINT SKYBLUE (-7075 2125);
FORCEPROP 1 LAST VOLTAGE 16V
J 2
(-7075 2175);
DISPLAY 0.617021 (-7075 2175);
PAINT SKYBLUE (-7075 2175);
FORCEPROP 1 LAST MATERIAL X7R
J 2
(-7075 2075);
DISPLAY 0.617021 (-7075 2075);
PAINT SKYBLUE (-7075 2075);
FORCEPROP 1 LASTPIN (-7025 2275) $PN 1
J 2
(-7035 2255);
DISPLAY 0.617021 (-7035 2255);
PAINT ORANGE (-7035 2255);
FORCEPROP 1 LASTPIN (-7025 2075) $PN 2
J 2
(-7035 2055);
DISPLAY 0.617021 (-7035 2055);
PAINT ORANGE (-7035 2055);
FORCEPROP 2 LAST CDS_LOCATION C1D11
J 2
(-7075 2275);
DISPLAY 0.617021 (-7075 2275);
PAINT AQUA (-7075 2275);
DISPLAY INVISIBLE (-7075 2275);
FORCEPROP 2 LAST CDS_LIB dev_discrete
J 0
(-7025 2175);
PAINT ORANGE (-7025 2175);
DISPLAY INVISIBLE (-7025 2175);
FORCEPROP 0 LAST ROOM HOT_SWAP
J 0
(-7075 2325);
DISPLAY 1.021277 (-7075 2325);
PAINT ORANGE (-7075 2325);
DISPLAY INVISIBLE (-7075 2325);
FORCEPROP 1 LAST PATH I53
J 2
(-7075 2325);
DISPLAY 0.978723 (-7075 2325);
PAINT WHITE (-7075 2325);
DISPLAY INVISIBLE (-7075 2325);
FORCEPROP 2 LAST CDS_SEC 1
J 0
(-7075 2325);
PAINT ORANGE (-7075 2325);
DISPLAY INVISIBLE (-7075 2325);
FORCEPROP 2 LAST SEC_TYPE 0402V
J 0
(-7075 2375);
DISPLAY 1.021277 (-7075 2375);
PAINT ORANGE (-7075 2375);
DISPLAY INVISIBLE (-7075 2375);
FORCEPROP 2 LAST SEC 1
J 0
(-7075 2375);
DISPLAY 0.680851 (-7075 2375);
PAINT MONO (-7075 2375);
DISPLAY INVISIBLE (-7075 2375);
FORCEADD RES..2
(-6725 2025);
FORCEPROP 1 LASTPIN (-6725 1925) $PN 2
J 0
(-6720 1935);
DISPLAY 0.617021 (-6720 1935);
PAINT ORANGE (-6720 1935);
FORCEPROP 1 LAST WATTAGE 1/16W
J 0
(-6685 2000);
DISPLAY 0.617021 (-6685 2000);
PAINT SKYBLUE (-6685 2000);
FORCEPROP 1 LAST MATERIAL CHIP
J 0
(-6685 1950);
DISPLAY 0.617021 (-6685 1950);
PAINT SKYBLUE (-6685 1950);
FORCEPROP 1 LAST PACK_TYPE 0402
J 0
(-6685 1850);
DISPLAY 0.617021 (-6685 1850);
PAINT SKYBLUE (-6685 1850);
FORCEPROP 1 LAST PART_NUMBER G21796-010
J 0
(-6685 1900);
DISPLAY 0.617021 (-6685 1900);
PAINT BLUE (-6685 1900);
FORCEPROP 1 LASTPIN (-6725 2125) $PN 1
J 0
(-6720 2087);
DISPLAY 0.617021 (-6720 2087);
PAINT ORANGE (-6720 2087);
FORCEPROP 1 LAST TOLERANCE 1%
J 0
(-6680 2050);
DISPLAY 0.617021 (-6680 2050);
PAINT SKYBLUE (-6680 2050);
FORCEPROP 1 LAST VALUE 100.0K
J 0
(-6680 2100);
DISPLAY 0.617021 (-6680 2100);
PAINT SKYBLUE (-6680 2100);
FORCEPROP 1 LAST LOCATION R9P23
J 0
(-6680 2150);
DISPLAY 0.617021 (-6680 2150);
PAINT AQUA (-6680 2150);
FORCEPROP 2 LAST CDS_LIB mstr_discrete
J 0
(-6725 2025);
PAINT ORANGE (-6725 2025);
DISPLAY INVISIBLE (-6725 2025);
FORCEPROP 2 LAST CDS_LOCATION R9P23
J 0
(-6680 2150);
DISPLAY 0.617021 (-6680 2150);
PAINT AQUA (-6680 2150);
DISPLAY INVISIBLE (-6680 2150);
FORCEPROP 0 LAST ROOM HOT_SWAP
J 0
(-6675 2200);
DISPLAY 1.021277 (-6675 2200);
PAINT ORANGE (-6675 2200);
DISPLAY INVISIBLE (-6675 2200);
FORCEPROP 1 LAST PATH I54
J 0
(-6675 2200);
DISPLAY 0.978723 (-6675 2200);
PAINT WHITE (-6675 2200);
DISPLAY INVISIBLE (-6675 2200);
FORCEPROP 2 LAST SEC_TYPE 0402
J 0
(-6675 2250);
DISPLAY 1.021277 (-6675 2250);
PAINT ORANGE (-6675 2250);
DISPLAY INVISIBLE (-6675 2250);
FORCEPROP 2 LAST SEC 1
J 0
(-6675 2250);
DISPLAY 0.680851 (-6675 2250);
PAINT MONO (-6675 2250);
DISPLAY INVISIBLE (-6675 2250);
FORCEADD RES..2
R 2
(-6725 1725);
FORCEPROP 1 LAST VALUE 12.1K
J 2
(-6770 1800);
DISPLAY 0.617021 (-6770 1800);
PAINT SKYBLUE (-6770 1800);
FORCEPROP 1 LAST PART_NUMBER G21796-089
J 2
(-6765 1600);
DISPLAY 0.617021 (-6765 1600);
PAINT BLUE (-6765 1600);
FORCEPROP 1 LAST LOCATION R9P24
J 2
(-6770 1850);
DISPLAY 0.617021 (-6770 1850);
PAINT AQUA (-6770 1850);
FORCEPROP 1 LAST WATTAGE 1/16W
J 2
(-6765 1700);
DISPLAY 0.617021 (-6765 1700);
PAINT SKYBLUE (-6765 1700);
FORCEPROP 1 LAST MATERIAL CHIP
J 2
(-6765 1650);
DISPLAY 0.617021 (-6765 1650);
PAINT SKYBLUE (-6765 1650);
FORCEPROP 1 LAST PACK_TYPE 0402
J 2
(-6765 1550);
DISPLAY 0.617021 (-6765 1550);
PAINT SKYBLUE (-6765 1550);
FORCEPROP 1 LAST TOLERANCE 1%
J 2
(-6770 1750);
DISPLAY 0.617021 (-6770 1750);
PAINT SKYBLUE (-6770 1750);
FORCEPROP 1 LASTPIN (-6725 1625) $PN 2
J 2
(-6730 1635);
DISPLAY 0.617021 (-6730 1635);
PAINT ORANGE (-6730 1635);
FORCEPROP 1 LASTPIN (-6725 1825) $PN 1
J 2
(-6730 1787);
DISPLAY 0.617021 (-6730 1787);
PAINT ORANGE (-6730 1787);
FORCEPROP 2 LAST CDS_LIB mstr_discrete
J 0
(-6725 1725);
PAINT ORANGE (-6725 1725);
DISPLAY INVISIBLE (-6725 1725);
FORCEPROP 2 LAST CDS_LOCATION R9P24
J 2
(-6770 1850);
DISPLAY 0.617021 (-6770 1850);
PAINT AQUA (-6770 1850);
DISPLAY INVISIBLE (-6770 1850);
FORCEPROP 2 LAST ROOM HOT_SWAP
J 2
(-6775 1900);
PAINT PEACH (-6775 1900);
DISPLAY INVISIBLE (-6775 1900);
FORCEPROP 1 LAST PATH I55
J 2
(-6775 1900);
DISPLAY 0.978723 (-6775 1900);
PAINT WHITE (-6775 1900);
DISPLAY INVISIBLE (-6775 1900);
FORCEPROP 2 LAST BOM_COST MIO_USB
J 2
(-6775 1900);
PAINT MONO (-6775 1900);
DISPLAY INVISIBLE (-6775 1900);
FORCEPROP 2 LAST SEC 1
J 0
(-6775 1950);
DISPLAY 0.680851 (-6775 1950);
PAINT MONO (-6775 1950);
DISPLAY INVISIBLE (-6775 1950);
FORCEPROP 2 LAST SEC_TYPE 0402
J 0
(-6775 1950);
DISPLAY 1.021277 (-6775 1950);
PAINT ORANGE (-6775 1950);
DISPLAY INVISIBLE (-6775 1950);
FORCEADD AGND0..1
(-6725 1525);
FORCEPROP 3 LASTPIN (-6725 1575) SIG_NAME AGND_HSC\g
J 0
(-6715 1585);
DISPLAY 0.659574 (-6715 1585);
PAINT MONO (-6715 1585);
DISPLAY INVISIBLE (-6715 1585);
FORCEPROP 1 LAST HDL_POWER AGND_HSC
J 1
(-6725 1475);
DISPLAY 0.617021 (-6725 1475);
PAINT GREEN (-6725 1475);
FORCEPROP 1 LAST BODY_TYPE PLUMBING
J 0
(-6770 1482);
DISPLAY 0.340426 (-6770 1482);
PAINT GREEN (-6770 1482);
DISPLAY INVISIBLE (-6770 1482);
FORCEPROP 2 LAST ROOM VR_P3V3
J 0
(-6750 1500);
PAINT ORANGE (-6750 1500);
DISPLAY INVISIBLE (-6750 1500);
FORCEPROP 2 LAST BOM_COST MIO_VRD_MAIN
J 0
(-6700 1500);
PAINT ORANGE (-6700 1500);
DISPLAY INVISIBLE (-6700 1500);
FORCEPROP 2 LAST CDS_LIB mstr_symbols
J 0
(-6725 1525);
PAINT ORANGE (-6725 1525);
DISPLAY INVISIBLE (-6725 1525);
FORCEPROP 1 LAST VOLTAGE 0
J 0
(-6725 1525);
PAINT SKYBLUE (-6725 1525);
DISPLAY INVISIBLE (-6725 1525);
FORCEPROP 1 LAST PATH I56
J 0
(-6650 1525);
DISPLAY 0.872340 (-6650 1525);
PAINT AQUA (-6650 1525);
DISPLAY INVISIBLE (-6650 1525);
FORCEADD NPN..1
(-1650 1650);
FORCEPROP 1 LASTPIN (-1600 1550) $PN 2
J 0
(-1575 1500);
DISPLAY 0.617021 (-1575 1500);
PAINT GREEN (-1575 1500);
FORCEPROP 1 LASTPIN (-1750 1650) $PN 1
J 0
(-1805 1675);
DISPLAY 0.617021 (-1805 1675);
PAINT GREEN (-1805 1675);
FORCEPROP 1 LASTPIN (-1600 1750) $PN 3
J 0
(-1581 1760);
DISPLAY 0.617021 (-1581 1760);
PAINT GREEN (-1581 1760);
FORCEPROP 1 LAST MATERIAL IC
J 0
(-1500 1600);
DISPLAY 0.617021 (-1500 1600);
PAINT SKYBLUE (-1500 1600);
FORCEPROP 1 LAST PACK_TYPE SM
J 0
(-1500 1550);
DISPLAY 0.617021 (-1500 1550);
PAINT SKYBLUE (-1500 1550);
FORCEPROP 1 LAST VALUE MMBT3904
J 0
(-1500 1650);
DISPLAY 0.617021 (-1500 1650);
PAINT SKYBLUE (-1500 1650);
FORCEPROP 1 LAST PART_NUMBER C52245-001
J 0
(-1500 1500);
DISPLAY 0.617021 (-1500 1500);
PAINT BLUE (-1500 1500);
FORCEPROP 1 LAST LOCATION Q1D3
J 0
(-1500 1700);
DISPLAY 0.617021 (-1500 1700);
PAINT AQUA (-1500 1700);
FORCEPROP 2 LAST CDS_LIB mstr_discrete
J 0
(-1650 1650);
PAINT ORANGE (-1650 1650);
DISPLAY INVISIBLE (-1650 1650);
FORCEPROP 0 LAST ROOM HOT_SWAP
J 0
(-1500 1800);
DISPLAY 1.021277 (-1500 1800);
PAINT ORANGE (-1500 1800);
DISPLAY INVISIBLE (-1500 1800);
FORCEPROP 1 LAST PATH I58
J 0
(-1500 1750);
DISPLAY 0.978723 (-1500 1750);
PAINT BLUE (-1500 1750);
DISPLAY INVISIBLE (-1500 1750);
FORCEPROP 2 LAST CDS_LOCATION Q1D3
J 0
(-1500 1700);
DISPLAY 0.617021 (-1500 1700);
PAINT AQUA (-1500 1700);
DISPLAY INVISIBLE (-1500 1700);
FORCEPROP 2 LAST SEC 1
J 0
(-1500 1800);
DISPLAY 0.680851 (-1500 1800);
PAINT MONO (-1500 1800);
DISPLAY INVISIBLE (-1500 1800);
FORCEPROP 2 LAST SEC_TYPE SM
J 0
(-1500 1800);
DISPLAY 1.021277 (-1500 1800);
PAINT ORANGE (-1500 1800);
DISPLAY INVISIBLE (-1500 1800);
FORCEADD GND..1
(-1600 1450);
FORCEPROP 3 LASTPIN (-1600 1500) SIG_NAME GND\g
J 0
(-1590 1510);
DISPLAY 0.659574 (-1590 1510);
PAINT MONO (-1590 1510);
DISPLAY INVISIBLE (-1590 1510);
FORCEPROP 1 LAST VOLTAGE 0
J 0
(-1600 1450);
PAINT SKYBLUE (-1600 1450);
DISPLAY INVISIBLE (-1600 1450);
FORCEPROP 2 LAST CDS_LIB mstr_symbols
J 0
(-1600 1450);
PAINT ORANGE (-1600 1450);
DISPLAY INVISIBLE (-1600 1450);
FORCEPROP 1 LAST BODY_TYPE PLUMBING
J 0
(-1645 1407);
DISPLAY 0.340426 (-1645 1407);
PAINT GREEN (-1645 1407);
DISPLAY INVISIBLE (-1645 1407);
FORCEPROP 1 LAST HDL_POWER GND
J 0
(-1600 1600);
DISPLAY 0.638298 (-1600 1600);
PAINT GREEN (-1600 1600);
DISPLAY INVISIBLE (-1600 1600);
FORCEPROP 1 LAST PATH I59
J 0
(-1525 1450);
DISPLAY 0.872340 (-1525 1450);
PAINT AQUA (-1525 1450);
DISPLAY INVISIBLE (-1525 1450);
FORCEPROP 1 LAST SIZE 1B
J 0
(-1525 1400);
DISPLAY 0.638298 (-1525 1400);
PAINT GREEN (-1525 1400);
DISPLAY INVISIBLE (-1525 1400);
FORCEADD RES..2
(-7200 4025);
FORCEPROP 1 LASTPIN (-7200 3925) $PN 2
J 0
(-7195 3935);
DISPLAY 0.617021 (-7195 3935);
PAINT ORANGE (-7195 3935);
FORCEPROP 1 LAST WATTAGE 1/16W
J 0
(-7160 4000);
DISPLAY 0.617021 (-7160 4000);
PAINT SKYBLUE (-7160 4000);
FORCEPROP 1 LAST MATERIAL CHIP
J 0
(-7160 3950);
DISPLAY 0.617021 (-7160 3950);
PAINT SKYBLUE (-7160 3950);
FORCEPROP 1 LAST PACK_TYPE 0402
J 0
(-7160 3850);
DISPLAY 0.617021 (-7160 3850);
PAINT SKYBLUE (-7160 3850);
FORCEPROP 1 LAST TOLERANCE 1%
J 0
(-7155 4050);
DISPLAY 0.617021 (-7155 4050);
PAINT SKYBLUE (-7155 4050);
FORCEPROP 1 LAST PART_NUMBER G21796-010
J 0
(-7160 3900);
DISPLAY 0.617021 (-7160 3900);
PAINT BLUE (-7160 3900);
FORCEPROP 1 LASTPIN (-7200 4125) $PN 1
J 0
(-7195 4087);
DISPLAY 0.617021 (-7195 4087);
PAINT ORANGE (-7195 4087);
FORCEPROP 1 LAST VALUE 100.0K
J 0
(-7155 4100);
DISPLAY 0.617021 (-7155 4100);
PAINT SKYBLUE (-7155 4100);
FORCEPROP 1 LAST LOCATION R9P28
J 0
(-7155 4150);
DISPLAY 0.617021 (-7155 4150);
PAINT AQUA (-7155 4150);
FORCEPROP 2 LAST CDS_LIB mstr_discrete
J 0
(-7200 4025);
PAINT ORANGE (-7200 4025);
DISPLAY INVISIBLE (-7200 4025);
FORCEPROP 1 LAST PATH I6
J 0
(-7150 4200);
DISPLAY 0.978723 (-7150 4200);
PAINT WHITE (-7150 4200);
DISPLAY INVISIBLE (-7150 4200);
FORCEPROP 2 LAST SEC_TYPE 0402
J 0
(-7150 4250);
DISPLAY 1.021277 (-7150 4250);
PAINT ORANGE (-7150 4250);
DISPLAY INVISIBLE (-7150 4250);
FORCEPROP 2 LAST CDS_LOCATION R9P28
J 0
(-7155 4150);
DISPLAY 0.617021 (-7155 4150);
PAINT AQUA (-7155 4150);
DISPLAY INVISIBLE (-7155 4150);
FORCEPROP 2 LAST SEC 1
J 0
(-7150 4250);
DISPLAY 0.680851 (-7150 4250);
PAINT MONO (-7150 4250);
DISPLAY INVISIBLE (-7150 4250);
FORCEPROP 0 LAST ROOM HOT_SWAP
J 0
(-7150 4200);
DISPLAY 1.021277 (-7150 4200);
PAINT ORANGE (-7150 4200);
DISPLAY INVISIBLE (-7150 4200);
FORCEADD OFFPAGE..2
(-825 3950);
FORCEPROP 2 LAST $XR0 118 
J 0
(-636 3950);
DISPLAY 0.638298 (-636 3950);
PAINT MONO (-636 3950);
FORCEPROP 2 LAST $XR1 146 
J 0
(-516 3950);
DISPLAY 0.638298 (-516 3950);
PAINT MONO (-516 3950);
FORCEPROP 2 LAST $XR2 170 
J 0
(-396 3950);
DISPLAY 0.638298 (-396 3950);
PAINT MONO (-396 3950);
FORCEPROP 1 LAST COMMENT_BODY TRUE
J 0
(-870 3855);
DISPLAY 0.872340 (-870 3855);
PAINT GREEN (-870 3855);
DISPLAY INVISIBLE (-870 3855);
FORCEPROP 2 LAST CDS_LIB mstr_standard
J 0
(-825 3950);
PAINT ORANGE (-825 3950);
DISPLAY INVISIBLE (-825 3950);
FORCEPROP 2 LAST PATH I63
J 0
(-650 4025);
DISPLAY 1.021277 (-650 4025);
PAINT ORANGE (-650 4025);
DISPLAY INVISIBLE (-650 4025);
FORCEPROP 1 LAST OFFPAGE TRUE
J 0
(-500 3825);
DISPLAY 0.872340 (-500 3825);
PAINT GREEN (-500 3825);
DISPLAY INVISIBLE (-500 3825);
FORCEADD OFFPAGE..2
(-825 2925);
FORCEPROP 2 LAST $XR0 200 
J 0
(-636 2925);
DISPLAY 0.638298 (-636 2925);
PAINT MONO (-636 2925);
FORCEPROP 1 LAST COMMENT_BODY TRUE
J 0
(-870 2830);
DISPLAY 0.872340 (-870 2830);
PAINT GREEN (-870 2830);
DISPLAY INVISIBLE (-870 2830);
FORCEPROP 2 LAST CDS_LIB mstr_standard
J 0
(-825 2925);
PAINT ORANGE (-825 2925);
DISPLAY INVISIBLE (-825 2925);
FORCEPROP 2 LAST PATH I64
J 0
(-650 3000);
DISPLAY 1.021277 (-650 3000);
PAINT ORANGE (-650 3000);
DISPLAY INVISIBLE (-650 3000);
FORCEPROP 1 LAST OFFPAGE TRUE
J 0
(-500 2800);
DISPLAY 0.872340 (-500 2800);
PAINT GREEN (-500 2800);
DISPLAY INVISIBLE (-500 2800);
FORCEADD RES..2
(-400 3025);
FORCEPROP 1 LASTPIN (-400 2925) $PN 2
J 0
(-395 2935);
DISPLAY 0.617021 (-395 2935);
PAINT ORANGE (-395 2935);
FORCEPROP 1 LAST WATTAGE 1/16W
J 0
(-360 3000);
DISPLAY 0.617021 (-360 3000);
PAINT SKYBLUE (-360 3000);
FORCEPROP 1 LAST MATERIAL CHIP
J 0
(-360 2950);
DISPLAY 0.617021 (-360 2950);
PAINT SKYBLUE (-360 2950);
FORCEPROP 1 LAST PACK_TYPE 0402
J 0
(-360 2850);
DISPLAY 0.617021 (-360 2850);
PAINT SKYBLUE (-360 2850);
FORCEPROP 1 LAST PART_NUMBER G21796-026
J 0
(-360 2900);
DISPLAY 0.617021 (-360 2900);
PAINT BLUE (-360 2900);
FORCEPROP 1 LAST TOLERANCE 1%
J 0
(-355 3050);
DISPLAY 0.617021 (-355 3050);
PAINT SKYBLUE (-355 3050);
FORCEPROP 1 LASTPIN (-400 3125) $PN 1
J 0
(-395 3087);
DISPLAY 0.617021 (-395 3087);
PAINT ORANGE (-395 3087);
FORCEPROP 1 LAST LOCATION R1D36
J 0
(-355 3150);
DISPLAY 0.617021 (-355 3150);
PAINT AQUA (-355 3150);
FORCEPROP 1 LAST VALUE 1.00K
J 0
(-355 3100);
DISPLAY 0.617021 (-355 3100);
PAINT SKYBLUE (-355 3100);
FORCEPROP 2 LAST CDS_LIB mstr_discrete
J 2
(-400 3025);
PAINT ORANGE (-400 3025);
DISPLAY INVISIBLE (-400 3025);
FORCEPROP 1 LAST PATH I65
J 0
(-350 3200);
DISPLAY 0.978723 (-350 3200);
PAINT WHITE (-350 3200);
DISPLAY INVISIBLE (-350 3200);
FORCEPROP 2 LAST ROOM HOT_SWAP
J 0
(-350 3200);
PAINT PEACH (-350 3200);
DISPLAY INVISIBLE (-350 3200);
FORCEPROP 2 LAST SEC 1
J 0
(-350 3250);
DISPLAY 0.680851 (-350 3250);
PAINT MONO (-350 3250);
DISPLAY INVISIBLE (-350 3250);
FORCEPROP 2 LAST CDS_LOCATION R1D36
J 0
(-355 3150);
DISPLAY 0.617021 (-355 3150);
PAINT AQUA (-355 3150);
DISPLAY INVISIBLE (-355 3150);
FORCEPROP 2 LAST BOM_COST MIO_USB
J 0
(-350 3200);
PAINT MONO (-350 3200);
DISPLAY INVISIBLE (-350 3200);
FORCEPROP 2 LAST SEC_TYPE 0402
J 0
(-350 3250);
DISPLAY 1.021277 (-350 3250);
PAINT ORANGE (-350 3250);
DISPLAY INVISIBLE (-350 3250);
FORCEADD CAP_A..1
(-400 2625);
FORCEPROP 1 LASTPIN (-400 2525) $PN 2
J 0
(-390 2505);
DISPLAY 0.617021 (-390 2505);
PAINT ORANGE (-390 2505);
FORCEPROP 1 LAST PACK_TYPE 0402V
J 0
(-350 2425);
DISPLAY 0.617021 (-350 2425);
PAINT SKYBLUE (-350 2425);
FORCEPROP 1 LAST PART_NUMBER A36096-030
J 0
(-350 2475);
DISPLAY 0.617021 (-350 2475);
PAINT BLUE (-350 2475);
FORCEPROP 1 LAST MATERIAL EMPTY
J 0
(-350 2525);
DISPLAY 0.617021 (-350 2525);
PAINT RED (-350 2525);
FORCEPROP 1 LASTPIN (-400 2725) $PN 1
J 0
(-390 2705);
DISPLAY 0.617021 (-390 2705);
PAINT ORANGE (-390 2705);
FORCEPROP 1 LAST VOLTAGE 16V
J 0
(-350 2625);
DISPLAY 0.617021 (-350 2625);
PAINT SKYBLUE (-350 2625);
FORCEPROP 1 LAST TOLERANCE 10%
J 0
(-350 2575);
DISPLAY 0.617021 (-350 2575);
PAINT SKYBLUE (-350 2575);
FORCEPROP 1 LAST VALUE 0.1UF
J 0
(-350 2675);
DISPLAY 0.617021 (-350 2675);
PAINT SKYBLUE (-350 2675);
FORCEPROP 1 LAST LOCATION C9P12
J 0
(-350 2725);
DISPLAY 0.617021 (-350 2725);
PAINT AQUA (-350 2725);
FORCEPROP 2 LAST CDS_LIB dev_discrete
J 0
(-400 2625);
PAINT ORANGE (-400 2625);
DISPLAY INVISIBLE (-400 2625);
FORCEPROP 1 LAST PATH I67
J 0
(-350 2775);
DISPLAY 0.978723 (-350 2775);
PAINT WHITE (-350 2775);
DISPLAY INVISIBLE (-350 2775);
FORCEPROP 2 LAST CDS_LOCATION C9P12
J 0
(-350 2725);
DISPLAY 0.617021 (-350 2725);
PAINT AQUA (-350 2725);
DISPLAY INVISIBLE (-350 2725);
FORCEPROP 0 LAST ROOM HOT_SWAP
J 2
(-350 2775);
DISPLAY 1.021277 (-350 2775);
PAINT ORANGE (-350 2775);
DISPLAY INVISIBLE (-350 2775);
FORCEPROP 2 LAST SEC 1
J 0
(-350 2825);
DISPLAY 0.680851 (-350 2825);
PAINT MONO (-350 2825);
DISPLAY INVISIBLE (-350 2825);
FORCEPROP 2 LAST SEC_TYPE 0402V
J 0
(-350 2825);
DISPLAY 1.021277 (-350 2825);
PAINT ORANGE (-350 2825);
DISPLAY INVISIBLE (-350 2825);
FORCEADD AGND0..1
(-400 2400);
FORCEPROP 3 LASTPIN (-400 2450) SIG_NAME AGND_HSC\g
J 0
(-390 2460);
DISPLAY 0.659574 (-390 2460);
PAINT MONO (-390 2460);
DISPLAY INVISIBLE (-390 2460);
FORCEPROP 1 LAST HDL_POWER AGND_HSC
J 1
(-400 2350);
DISPLAY 0.617021 (-400 2350);
PAINT GREEN (-400 2350);
FORCEPROP 2 LAST ROOM VR_P3V3
J 0
(-425 2375);
PAINT ORANGE (-425 2375);
DISPLAY INVISIBLE (-425 2375);
FORCEPROP 1 LAST BODY_TYPE PLUMBING
J 0
(-445 2357);
DISPLAY 0.340426 (-445 2357);
PAINT GREEN (-445 2357);
DISPLAY INVISIBLE (-445 2357);
FORCEPROP 2 LAST CDS_LIB mstr_symbols
J 0
(-400 2400);
PAINT ORANGE (-400 2400);
DISPLAY INVISIBLE (-400 2400);
FORCEPROP 1 LAST VOLTAGE 0
J 0
(-400 2400);
PAINT SKYBLUE (-400 2400);
DISPLAY INVISIBLE (-400 2400);
FORCEPROP 1 LAST PATH I68
J 0
(-325 2400);
DISPLAY 0.872340 (-325 2400);
PAINT AQUA (-325 2400);
DISPLAY INVISIBLE (-325 2400);
FORCEPROP 2 LAST BOM_COST MIO_VRD_MAIN
J 0
(-375 2375);
PAINT ORANGE (-375 2375);
DISPLAY INVISIBLE (-375 2375);
FORCEADD OFFPAGE..2
(-825 2725);
FORCEPROP 2 LAST $XR0 200 
J 0
(-636 2725);
DISPLAY 0.638298 (-636 2725);
PAINT MONO (-636 2725);
FORCEPROP 2 LAST CDS_LIB mstr_standard
J 0
(-825 2725);
PAINT ORANGE (-825 2725);
DISPLAY INVISIBLE (-825 2725);
FORCEPROP 1 LAST COMMENT_BODY TRUE
J 0
(-870 2630);
DISPLAY 0.872340 (-870 2630);
PAINT GREEN (-870 2630);
DISPLAY INVISIBLE (-870 2630);
FORCEPROP 2 LAST PATH I69
J 0
(-650 2800);
DISPLAY 1.021277 (-650 2800);
PAINT ORANGE (-650 2800);
DISPLAY INVISIBLE (-650 2800);
FORCEPROP 1 LAST OFFPAGE TRUE
J 0
(-500 2600);
DISPLAY 0.872340 (-500 2600);
PAINT GREEN (-500 2600);
DISPLAY INVISIBLE (-500 2600);
FORCEADD CAP_A..1
R 2
(-6775 3575);
FORCEPROP 1 LAST PART_NUMBER A36096-030
J 2
(-6825 3425);
DISPLAY 0.617021 (-6825 3425);
PAINT BLUE (-6825 3425);
FORCEPROP 1 LAST TOLERANCE 10%
J 2
(-6825 3525);
DISPLAY 0.617021 (-6825 3525);
PAINT SKYBLUE (-6825 3525);
FORCEPROP 1 LAST PACK_TYPE 0402V
J 2
(-6825 3375);
DISPLAY 0.617021 (-6825 3375);
PAINT SKYBLUE (-6825 3375);
FORCEPROP 1 LAST MATERIAL X7R
J 2
(-6825 3475);
DISPLAY 0.617021 (-6825 3475);
PAINT SKYBLUE (-6825 3475);
FORCEPROP 1 LASTPIN (-6775 3475) $PN 2
J 2
(-6785 3455);
DISPLAY 0.617021 (-6785 3455);
PAINT ORANGE (-6785 3455);
FORCEPROP 1 LAST VOLTAGE 16V
J 2
(-6825 3575);
DISPLAY 0.617021 (-6825 3575);
PAINT SKYBLUE (-6825 3575);
FORCEPROP 1 LAST VALUE 0.1UF
J 2
(-6825 3625);
DISPLAY 0.617021 (-6825 3625);
PAINT SKYBLUE (-6825 3625);
FORCEPROP 1 LAST LOCATION C1D27
J 2
(-6825 3675);
DISPLAY 0.617021 (-6825 3675);
PAINT AQUA (-6825 3675);
FORCEPROP 1 LASTPIN (-6775 3675) $PN 1
J 2
(-6785 3655);
DISPLAY 0.617021 (-6785 3655);
PAINT ORANGE (-6785 3655);
FORCEPROP 2 LAST CDS_LIB dev_discrete
J 0
(-6775 3575);
PAINT ORANGE (-6775 3575);
DISPLAY INVISIBLE (-6775 3575);
FORCEPROP 2 LAST SEC 1
J 0
(-6825 3775);
DISPLAY 0.680851 (-6825 3775);
PAINT MONO (-6825 3775);
DISPLAY INVISIBLE (-6825 3775);
FORCEPROP 2 LAST SEC_TYPE 0402V
J 0
(-6825 3775);
DISPLAY 1.021277 (-6825 3775);
PAINT ORANGE (-6825 3775);
DISPLAY INVISIBLE (-6825 3775);
FORCEPROP 2 LAST CDS_SEC 1
J 0
(-6825 3725);
PAINT ORANGE (-6825 3725);
DISPLAY INVISIBLE (-6825 3725);
FORCEPROP 1 LAST PATH I7
J 2
(-6825 3725);
DISPLAY 0.978723 (-6825 3725);
PAINT WHITE (-6825 3725);
DISPLAY INVISIBLE (-6825 3725);
FORCEPROP 0 LAST ROOM HOT_SWAP
J 0
(-6825 3725);
DISPLAY 1.021277 (-6825 3725);
PAINT ORANGE (-6825 3725);
DISPLAY INVISIBLE (-6825 3725);
FORCEPROP 2 LAST CDS_LOCATION C1D27
J 2
(-6825 3675);
DISPLAY 0.617021 (-6825 3675);
PAINT AQUA (-6825 3675);
DISPLAY INVISIBLE (-6825 3675);
FORCEADD OFFPAGE..2
(-775 2075);
FORCEPROP 2 LAST $XR0 200 
J 0
(-586 2075);
DISPLAY 0.638298 (-586 2075);
PAINT MONO (-586 2075);
FORCEPROP 1 LAST COMMENT_BODY TRUE
J 0
(-820 1980);
DISPLAY 0.872340 (-820 1980);
PAINT GREEN (-820 1980);
DISPLAY INVISIBLE (-820 1980);
FORCEPROP 1 LAST OFFPAGE TRUE
J 0
(-450 1950);
DISPLAY 0.872340 (-450 1950);
PAINT GREEN (-450 1950);
DISPLAY INVISIBLE (-450 1950);
FORCEPROP 2 LAST CDS_LIB mstr_standard
J 0
(-775 2075);
PAINT ORANGE (-775 2075);
DISPLAY INVISIBLE (-775 2075);
FORCEPROP 2 LAST PATH I71
J 0
(-600 2150);
DISPLAY 1.021277 (-600 2150);
PAINT ORANGE (-600 2150);
DISPLAY INVISIBLE (-600 2150);
FORCEADD OFFPAGE..2
(-775 2025);
FORCEPROP 2 LAST $XR0 200 
J 0
(-586 2025);
DISPLAY 0.638298 (-586 2025);
PAINT MONO (-586 2025);
FORCEPROP 1 LAST COMMENT_BODY TRUE
J 0
(-820 1930);
DISPLAY 0.872340 (-820 1930);
PAINT GREEN (-820 1930);
DISPLAY INVISIBLE (-820 1930);
FORCEPROP 1 LAST OFFPAGE TRUE
J 0
(-450 1900);
DISPLAY 0.872340 (-450 1900);
PAINT GREEN (-450 1900);
DISPLAY INVISIBLE (-450 1900);
FORCEPROP 2 LAST CDS_LIB mstr_standard
J 0
(-775 2025);
PAINT ORANGE (-775 2025);
DISPLAY INVISIBLE (-775 2025);
FORCEPROP 2 LAST PATH I72
J 0
(-600 2100);
DISPLAY 1.021277 (-600 2100);
PAINT ORANGE (-600 2100);
DISPLAY INVISIBLE (-600 2100);
FORCEADD OFFPAGE..2
(-775 1975);
FORCEPROP 2 LAST $XR0 200 
J 0
(-586 1975);
DISPLAY 0.638298 (-586 1975);
PAINT MONO (-586 1975);
FORCEPROP 1 LAST COMMENT_BODY TRUE
J 0
(-820 1880);
DISPLAY 0.872340 (-820 1880);
PAINT GREEN (-820 1880);
DISPLAY INVISIBLE (-820 1880);
FORCEPROP 2 LAST CDS_LIB mstr_standard
J 0
(-775 1975);
PAINT ORANGE (-775 1975);
DISPLAY INVISIBLE (-775 1975);
FORCEPROP 1 LAST OFFPAGE TRUE
J 0
(-450 1850);
DISPLAY 0.872340 (-450 1850);
PAINT GREEN (-450 1850);
DISPLAY INVISIBLE (-450 1850);
FORCEPROP 2 LAST PATH I73
J 0
(-600 2050);
DISPLAY 1.021277 (-600 2050);
PAINT ORANGE (-600 2050);
DISPLAY INVISIBLE (-600 2050);
FORCEADD OFFPAGE..2
(-775 1925);
FORCEPROP 2 LAST $XR0 200 
J 0
(-586 1925);
DISPLAY 0.638298 (-586 1925);
PAINT MONO (-586 1925);
FORCEPROP 1 LAST COMMENT_BODY TRUE
J 0
(-820 1830);
DISPLAY 0.872340 (-820 1830);
PAINT GREEN (-820 1830);
DISPLAY INVISIBLE (-820 1830);
FORCEPROP 2 LAST CDS_LIB mstr_standard
J 0
(-775 1925);
PAINT ORANGE (-775 1925);
DISPLAY INVISIBLE (-775 1925);
FORCEPROP 2 LAST PATH I74
J 0
(-600 2000);
DISPLAY 1.021277 (-600 2000);
PAINT ORANGE (-600 2000);
DISPLAY INVISIBLE (-600 2000);
FORCEPROP 1 LAST OFFPAGE TRUE
J 0
(-450 1800);
DISPLAY 0.872340 (-450 1800);
PAINT GREEN (-450 1800);
DISPLAY INVISIBLE (-450 1800);
FORCEADD P12V_STBY..1
(-400 3600);
FORCEPROP 3 LASTPIN (-400 3550) SIG_NAME P12V_STBY\g
J 0
(-390 3560);
DISPLAY 0.659574 (-390 3560);
PAINT MONO (-390 3560);
DISPLAY INVISIBLE (-390 3560);
FORCEPROP 1 LAST HDL_POWER P12V_STBY
J 0
(-700 3475);
DISPLAY 0.872340 (-700 3475);
PAINT ORANGE (-700 3475);
DISPLAY INVISIBLE (-700 3475);
FORCEPROP 1 LAST BODY_TYPE PLUMBING
J 0
(-445 3557);
DISPLAY 0.340426 (-445 3557);
PAINT GREEN (-445 3557);
DISPLAY INVISIBLE (-445 3557);
FORCEPROP 1 LAST VOLTAGE 12.0V
J 0
(-445 3557);
DISPLAY 0.340426 (-445 3557);
PAINT SKYBLUE (-445 3557);
DISPLAY INVISIBLE (-445 3557);
FORCEPROP 2 LAST CDS_LIB mstr_symbols
J 0
(-400 3600);
PAINT ORANGE (-400 3600);
DISPLAY INVISIBLE (-400 3600);
FORCEPROP 1 LAST SIZE 1B
J 0
(-355 3622);
DISPLAY 0.340426 (-355 3622);
PAINT GREEN (-355 3622);
DISPLAY INVISIBLE (-355 3622);
FORCEPROP 1 LAST PATH I75
J 0
(-355 3602);
DISPLAY 0.340426 (-355 3602);
PAINT GREEN (-355 3602);
DISPLAY INVISIBLE (-355 3602);
FORCEADD P12V_STBY..1
(-6725 2250);
FORCEPROP 3 LASTPIN (-6725 2200) SIG_NAME P12V_STBY\g
J 0
(-6715 2210);
DISPLAY 0.659574 (-6715 2210);
PAINT MONO (-6715 2210);
DISPLAY INVISIBLE (-6715 2210);
FORCEPROP 1 LAST HDL_POWER P12V_STBY
J 0
(-7025 2125);
DISPLAY 0.872340 (-7025 2125);
PAINT ORANGE (-7025 2125);
DISPLAY INVISIBLE (-7025 2125);
FORCEPROP 1 LAST VOLTAGE 12.0V
J 0
(-6770 2207);
DISPLAY 0.340426 (-6770 2207);
PAINT SKYBLUE (-6770 2207);
DISPLAY INVISIBLE (-6770 2207);
FORCEPROP 1 LAST SIZE 1B
J 0
(-6680 2272);
DISPLAY 0.340426 (-6680 2272);
PAINT GREEN (-6680 2272);
DISPLAY INVISIBLE (-6680 2272);
FORCEPROP 2 LAST CDS_LIB mstr_symbols
J 0
(-6725 2250);
PAINT ORANGE (-6725 2250);
DISPLAY INVISIBLE (-6725 2250);
FORCEPROP 1 LAST BODY_TYPE PLUMBING
J 0
(-6770 2207);
DISPLAY 0.340426 (-6770 2207);
PAINT GREEN (-6770 2207);
DISPLAY INVISIBLE (-6770 2207);
FORCEPROP 1 LAST PATH I76
J 0
(-6680 2252);
DISPLAY 0.340426 (-6680 2252);
PAINT GREEN (-6680 2252);
DISPLAY INVISIBLE (-6680 2252);
FORCEADD P12V_STBY..1
(-3125 1275);
FORCEPROP 3 LASTPIN (-3125 1225) SIG_NAME P12V_STBY\g
J 0
(-3115 1235);
DISPLAY 0.659574 (-3115 1235);
PAINT MONO (-3115 1235);
DISPLAY INVISIBLE (-3115 1235);
FORCEPROP 1 LAST HDL_POWER P12V_STBY
J 0
(-3425 1150);
DISPLAY 0.872340 (-3425 1150);
PAINT ORANGE (-3425 1150);
DISPLAY INVISIBLE (-3425 1150);
FORCEPROP 1 LAST BODY_TYPE PLUMBING
J 0
(-3170 1232);
DISPLAY 0.340426 (-3170 1232);
PAINT GREEN (-3170 1232);
DISPLAY INVISIBLE (-3170 1232);
FORCEPROP 1 LAST VOLTAGE 12.0V
J 0
(-3170 1232);
DISPLAY 0.340426 (-3170 1232);
PAINT SKYBLUE (-3170 1232);
DISPLAY INVISIBLE (-3170 1232);
FORCEPROP 1 LAST PATH I77
J 0
(-3080 1277);
DISPLAY 0.340426 (-3080 1277);
PAINT GREEN (-3080 1277);
DISPLAY INVISIBLE (-3080 1277);
FORCEPROP 2 LAST CDS_LIB mstr_symbols
J 0
(-3125 1275);
PAINT ORANGE (-3125 1275);
DISPLAY INVISIBLE (-3125 1275);
FORCEPROP 1 LAST SIZE 1B
J 0
(-3080 1297);
DISPLAY 0.340426 (-3080 1297);
PAINT GREEN (-3080 1297);
DISPLAY INVISIBLE (-3080 1297);
FORCEADD P12V_PSU..1
(-6675 4425);
FORCEPROP 3 LASTPIN (-6675 4375) SIG_NAME P12V_PSU\g
J 0
(-6665 4385);
DISPLAY 0.659574 (-6665 4385);
PAINT MONO (-6665 4385);
DISPLAY INVISIBLE (-6665 4385);
FORCEPROP 1 LAST VOLTAGE 12.0
J 0
(-6720 4382);
DISPLAY 0.340426 (-6720 4382);
PAINT SKYBLUE (-6720 4382);
DISPLAY INVISIBLE (-6720 4382);
FORCEPROP 2 LAST BOM_COST NT_BASE_VRD
J 0
(-6675 4525);
DISPLAY 0.617021 (-6675 4525);
PAINT ORANGE (-6675 4525);
DISPLAY INVISIBLE (-6675 4525);
FORCEPROP 2 LAST CDS_LIB mstr_symbols
J 0
(-6675 4425);
PAINT ORANGE (-6675 4425);
DISPLAY INVISIBLE (-6675 4425);
FORCEPROP 1 LAST BODY_TYPE PLUMBING
J 0
(-6720 4382);
DISPLAY 0.340426 (-6720 4382);
PAINT GREEN (-6720 4382);
DISPLAY INVISIBLE (-6720 4382);
FORCEPROP 2 LAST ROOM P2V5_LAN_AUX_VR
J 0
(-6675 4525);
DISPLAY 0.617021 (-6675 4525);
PAINT ORANGE (-6675 4525);
DISPLAY INVISIBLE (-6675 4525);
FORCEPROP 1 LAST HDL_POWER P12V_PSU
J 1
(-6675 4475);
DISPLAY 0.872340 (-6675 4475);
PAINT GREEN (-6675 4475);
DISPLAY INVISIBLE (-6675 4475);
FORCEPROP 1 LAST PATH I79
J 0
(-6625 4450);
DISPLAY 0.872340 (-6625 4450);
PAINT AQUA (-6625 4450);
DISPLAY INVISIBLE (-6625 4450);
FORCEADD FET_N_DUAL..5
(-6600 400);
FORCEPROP 1 LASTPIN (-6800 300) $PN 5
J 2
(-6797 315);
DISPLAY 0.617021 (-6797 315);
PAINT WHITE (-6797 315);
FORCEPROP 1 LASTPIN (-6600 200) $PN 4
J 2
(-6517 225);
DISPLAY 0.617021 (-6517 225);
PAINT WHITE (-6517 225);
FORCEPROP 1 LAST MATERIAL FET
J 0
(-6400 300);
DISPLAY 0.617021 (-6400 300);
PAINT SKYBLUE (-6400 300);
FORCEPROP 1 LAST VALUE 2N7002DW
J 0
(-6400 350);
DISPLAY 0.617021 (-6400 350);
PAINT SKYBLUE (-6400 350);
FORCEPROP 1 LAST PART_NUMBER D24280-001
J 0
(-6450 250);
DISPLAY 0.617021 (-6450 250);
PAINT BLUE (-6450 250);
FORCEPROP 1 LAST LOCATION Q1D1
J 0
(-6400 400);
DISPLAY 0.617021 (-6400 400);
PAINT AQUA (-6400 400);
FORCEPROP 1 LASTPIN (-6600 600) $PN 3
J 2
(-6547 565);
DISPLAY 0.617021 (-6547 565);
PAINT WHITE (-6547 565);
FORCEPROP 2 LAST CDS_LIB mstr_discrete
J 0
(-6600 400);
PAINT ORANGE (-6600 400);
DISPLAY INVISIBLE (-6600 400);
FORCEPROP 1 LAST PATH I82
J 0
(-6400 450);
DISPLAY 0.978723 (-6400 450);
PAINT BLUE (-6400 450);
DISPLAY INVISIBLE (-6400 450);
FORCEPROP 2 LAST CDS_LOCATION Q1D1
J 0
(-6400 400);
DISPLAY 0.617021 (-6400 400);
PAINT AQUA (-6400 400);
DISPLAY INVISIBLE (-6400 400);
FORCEPROP 1 LAST PACK_TYPE SMLF
J 0
(-6400 250);
DISPLAY 0.978723 (-6400 250);
PAINT SKYBLUE (-6400 250);
DISPLAY INVISIBLE (-6400 250);
FORCEPROP 2 LAST SEC 2
J 0
(-6400 500);
DISPLAY 0.680851 (-6400 500);
PAINT MONO (-6400 500);
DISPLAY INVISIBLE (-6400 500);
FORCEPROP 2 LAST SEC_TYPE SMLF
J 0
(-6400 500);
DISPLAY 1.021277 (-6400 500);
PAINT ORANGE (-6400 500);
DISPLAY INVISIBLE (-6400 500);
FORCEPROP 2 LAST ROOM HOT_SWAP
J 0
(-6450 550);
PAINT MONO (-6450 550);
DISPLAY INVISIBLE (-6450 550);
FORCEADD AGND0..1
(-5875 -25);
FORCEPROP 3 LASTPIN (-5875 25) SIG_NAME AGND_HSC\g
J 0
(-5865 35);
DISPLAY 0.659574 (-5865 35);
PAINT MONO (-5865 35);
DISPLAY INVISIBLE (-5865 35);
FORCEPROP 1 LAST HDL_POWER AGND_HSC
J 1
(-5875 -75);
DISPLAY 0.617021 (-5875 -75);
PAINT GREEN (-5875 -75);
FORCEPROP 2 LAST ROOM VR_P3V3
J 0
(-5900 -50);
PAINT ORANGE (-5900 -50);
DISPLAY INVISIBLE (-5900 -50);
FORCEPROP 1 LAST BODY_TYPE PLUMBING
J 0
(-5920 -68);
DISPLAY 0.340426 (-5920 -68);
PAINT GREEN (-5920 -68);
DISPLAY INVISIBLE (-5920 -68);
FORCEPROP 2 LAST BOM_COST MIO_VRD_MAIN
J 0
(-5850 -50);
PAINT ORANGE (-5850 -50);
DISPLAY INVISIBLE (-5850 -50);
FORCEPROP 1 LAST PATH I83
J 0
(-5800 -25);
DISPLAY 0.872340 (-5800 -25);
PAINT AQUA (-5800 -25);
DISPLAY INVISIBLE (-5800 -25);
FORCEPROP 2 LAST CDS_LIB mstr_symbols
J 0
(-5875 -25);
PAINT ORANGE (-5875 -25);
DISPLAY INVISIBLE (-5875 -25);
FORCEPROP 1 LAST VOLTAGE 0
J 0
(-5875 -25);
PAINT SKYBLUE (-5875 -25);
DISPLAY INVISIBLE (-5875 -25);
FORCEADD RES..1
R 1
(-6600 925);
FORCEPROP 1 LAST VALUE 90.9K
R 1
J 2
(-6550 850);
DISPLAY 0.617021 (-6550 850);
PAINT SKYBLUE (-6550 850);
FORCEPROP 1 LAST WATTAGE 1/16W
R 1
J 2
(-6475 875);
DISPLAY 0.617021 (-6475 875);
PAINT SKYBLUE (-6475 875);
FORCEPROP 1 LASTPIN (-6600 825) $PN 1
R 1
J 0
(-6612 837);
DISPLAY 0.617021 (-6612 837);
PAINT ORANGE (-6612 837);
FORCEPROP 1 LASTPIN (-6600 1025) $PN 2
R 1
J 0
(-6612 987);
DISPLAY 0.617021 (-6612 987);
PAINT ORANGE (-6612 987);
FORCEPROP 1 LAST TOLERANCE 1%
R 1
J 0
(-6525 900);
DISPLAY 0.617021 (-6525 900);
PAINT SKYBLUE (-6525 900);
FORCEPROP 1 LAST MATERIAL CHIP
R 1
J 0
(-6475 950);
DISPLAY 0.617021 (-6475 950);
PAINT SKYBLUE (-6475 950);
FORCEPROP 1 LAST PACK_TYPE 0402
R 1
J 0
(-6550 1000);
DISPLAY 0.617021 (-6550 1000);
PAINT SKYBLUE (-6550 1000);
FORCEPROP 1 LAST PART_NUMBER G21796-058
R 1
J 0
(-6650 750);
DISPLAY 0.617021 (-6650 750);
PAINT BLUE (-6650 750);
FORCEPROP 1 LAST LOCATION R1D13
J 0
(-6800 1020);
DISPLAY 0.617021 (-6800 1020);
PAINT AQUA (-6800 1020);
FORCEPROP 2 LAST ROOM HOT_SWAP
R 1
J 0
(-6775 975);
PAINT MONO (-6775 975);
DISPLAY INVISIBLE (-6775 975);
FORCEPROP 1 LAST PATH I84
R 1
J 0
(-6750 875);
DISPLAY 0.978723 (-6750 875);
PAINT WHITE (-6750 875);
DISPLAY INVISIBLE (-6750 875);
FORCEPROP 2 LAST CDS_LIB mstr_discrete
R 1
J 0
(-6600 925);
PAINT ORANGE (-6600 925);
DISPLAY INVISIBLE (-6600 925);
FORCEPROP 2 LAST CDS_LOCATION R1D13
J 0
(-6800 1020);
DISPLAY 0.617021 (-6800 1020);
PAINT AQUA (-6800 1020);
DISPLAY INVISIBLE (-6800 1020);
FORCEPROP 2 LAST SEC_TYPE 0402
J 0
(-6775 1100);
DISPLAY 1.021277 (-6775 1100);
PAINT ORANGE (-6775 1100);
DISPLAY INVISIBLE (-6775 1100);
FORCEPROP 2 LAST SEC 1
J 0
(-6775 1100);
DISPLAY 0.680851 (-6775 1100);
PAINT MONO (-6775 1100);
DISPLAY INVISIBLE (-6775 1100);
FORCEPROP 0 LAST NO_XNET_CONNECTION 1
J 0
(-6800 1050);
PAINT MONO (-6800 1050);
DISPLAY INVISIBLE (-6800 1050);
FORCEADD RES..2
(-5875 875);
FORCEPROP 1 LAST MATERIAL CHIP
J 0
(-5835 800);
DISPLAY 0.617021 (-5835 800);
PAINT SKYBLUE (-5835 800);
FORCEPROP 1 LAST PACK_TYPE 0402
J 0
(-5835 700);
DISPLAY 0.617021 (-5835 700);
PAINT SKYBLUE (-5835 700);
FORCEPROP 1 LASTPIN (-5875 975) $PN 1
J 0
(-5870 937);
DISPLAY 0.617021 (-5870 937);
PAINT ORANGE (-5870 937);
FORCEPROP 1 LAST VALUE 69.8K
J 0
(-5830 950);
DISPLAY 0.617021 (-5830 950);
PAINT SKYBLUE (-5830 950);
FORCEPROP 1 LAST TOLERANCE 1%
J 0
(-5830 900);
DISPLAY 0.617021 (-5830 900);
PAINT SKYBLUE (-5830 900);
FORCEPROP 1 LAST WATTAGE 1/16W
J 0
(-5835 850);
DISPLAY 0.617021 (-5835 850);
PAINT SKYBLUE (-5835 850);
FORCEPROP 1 LASTPIN (-5875 775) $PN 2
J 0
(-5870 785);
DISPLAY 0.617021 (-5870 785);
PAINT ORANGE (-5870 785);
FORCEPROP 1 LAST PART_NUMBER G21796-007
J 0
(-5835 750);
DISPLAY 0.617021 (-5835 750);
PAINT BLUE (-5835 750);
FORCEPROP 1 LAST LOCATION R1D16
J 0
(-5830 1000);
DISPLAY 0.617021 (-5830 1000);
PAINT AQUA (-5830 1000);
FORCEPROP 2 LAST CDS_LIB mstr_discrete
J 0
(-5875 875);
PAINT ORANGE (-5875 875);
DISPLAY INVISIBLE (-5875 875);
FORCEPROP 2 LAST CDS_LOCATION R1D16
J 0
(-5830 1000);
DISPLAY 0.617021 (-5830 1000);
PAINT AQUA (-5830 1000);
DISPLAY INVISIBLE (-5830 1000);
FORCEPROP 2 LAST SEC_TYPE 0402
J 0
(-5825 1100);
DISPLAY 1.021277 (-5825 1100);
PAINT ORANGE (-5825 1100);
DISPLAY INVISIBLE (-5825 1100);
FORCEPROP 2 LAST SEC 1
J 0
(-5825 1100);
DISPLAY 0.680851 (-5825 1100);
PAINT MONO (-5825 1100);
DISPLAY INVISIBLE (-5825 1100);
FORCEPROP 0 LAST NO_XNET_CONNECTION 1
J 0
(-5825 1100);
PAINT MONO (-5825 1100);
DISPLAY INVISIBLE (-5825 1100);
FORCEPROP 1 LAST PATH I85
J 0
(-5825 1050);
DISPLAY 0.978723 (-5825 1050);
PAINT WHITE (-5825 1050);
DISPLAY INVISIBLE (-5825 1050);
FORCEPROP 2 LAST ROOM HOT_SWAP
J 0
(-5825 1050);
PAINT MONO (-5825 1050);
DISPLAY INVISIBLE (-5825 1050);
FORCEADD FET_N_DUAL..5
(-5875 275);
FORCEPROP 1 LASTPIN (-6075 175) $PN 2
J 2
(-6072 190);
DISPLAY 0.617021 (-6072 190);
PAINT WHITE (-6072 190);
FORCEPROP 1 LASTPIN (-5875 75) $PN 1
J 2
(-5817 75);
DISPLAY 0.617021 (-5817 75);
PAINT WHITE (-5817 75);
FORCEPROP 1 LASTPIN (-5875 475) $PN 6
J 2
(-5822 440);
DISPLAY 0.617021 (-5822 440);
PAINT WHITE (-5822 440);
FORCEPROP 1 LAST MATERIAL FET
J 0
(-5675 175);
DISPLAY 0.617021 (-5675 175);
PAINT SKYBLUE (-5675 175);
FORCEPROP 1 LAST VALUE 2N7002DW
J 0
(-5675 225);
DISPLAY 0.617021 (-5675 225);
PAINT SKYBLUE (-5675 225);
FORCEPROP 1 LAST PART_NUMBER D24280-001
J 0
(-5675 125);
DISPLAY 0.617021 (-5675 125);
PAINT BLUE (-5675 125);
FORCEPROP 1 LAST LOCATION Q1D1
J 0
(-5675 275);
DISPLAY 0.617021 (-5675 275);
PAINT AQUA (-5675 275);
FORCEPROP 1 LAST PACK_TYPE SMLF
J 0
(-5675 125);
DISPLAY 0.978723 (-5675 125);
PAINT SKYBLUE (-5675 125);
DISPLAY INVISIBLE (-5675 125);
FORCEPROP 2 LAST CDS_LIB mstr_discrete
J 0
(-5875 275);
PAINT ORANGE (-5875 275);
DISPLAY INVISIBLE (-5875 275);
FORCEPROP 2 LAST SEC_TYPE SMLF
J 0
(-5675 375);
DISPLAY 1.021277 (-5675 375);
PAINT ORANGE (-5675 375);
DISPLAY INVISIBLE (-5675 375);
FORCEPROP 2 LAST SEC 1
J 0
(-5675 375);
DISPLAY 0.680851 (-5675 375);
PAINT MONO (-5675 375);
DISPLAY INVISIBLE (-5675 375);
FORCEPROP 2 LAST CDS_LOCATION Q1D1
J 0
(-5675 275);
DISPLAY 0.617021 (-5675 275);
PAINT AQUA (-5675 275);
DISPLAY INVISIBLE (-5675 275);
FORCEPROP 1 LAST PATH I86
J 0
(-5675 325);
DISPLAY 0.978723 (-5675 325);
PAINT BLUE (-5675 325);
DISPLAY INVISIBLE (-5675 325);
FORCEPROP 2 LAST ROOM HOT_SWAP
J 0
(-5675 375);
PAINT MONO (-5675 375);
DISPLAY INVISIBLE (-5675 375);
FORCEADD RES..2
(-6950 -50);
FORCEPROP 1 LASTPIN (-6950 -150) $PN 2
J 0
(-6945 -140);
DISPLAY 0.617021 (-6945 -140);
PAINT ORANGE (-6945 -140);
FORCEPROP 1 LAST WATTAGE 1/16W
J 0
(-6910 -75);
DISPLAY 0.617021 (-6910 -75);
PAINT SKYBLUE (-6910 -75);
FORCEPROP 1 LAST MATERIAL CHIP
J 0
(-6910 -125);
DISPLAY 0.617021 (-6910 -125);
PAINT SKYBLUE (-6910 -125);
FORCEPROP 1 LAST PACK_TYPE 0402
J 0
(-6910 -225);
DISPLAY 0.617021 (-6910 -225);
PAINT SKYBLUE (-6910 -225);
FORCEPROP 1 LAST PART_NUMBER G21796-010
J 0
(-6910 -175);
DISPLAY 0.617021 (-6910 -175);
PAINT BLUE (-6910 -175);
FORCEPROP 1 LAST TOLERANCE 1%
J 0
(-6905 -25);
DISPLAY 0.617021 (-6905 -25);
PAINT SKYBLUE (-6905 -25);
FORCEPROP 1 LASTPIN (-6950 50) $PN 1
J 0
(-6945 12);
DISPLAY 0.617021 (-6945 12);
PAINT ORANGE (-6945 12);
FORCEPROP 1 LAST LOCATION R1D18
J 0
(-6905 75);
DISPLAY 0.617021 (-6905 75);
PAINT AQUA (-6905 75);
FORCEPROP 1 LAST VALUE 100.0K
J 0
(-6905 25);
DISPLAY 0.617021 (-6905 25);
PAINT SKYBLUE (-6905 25);
FORCEPROP 2 LAST CDS_LIB mstr_discrete
J 0
(-6950 -50);
PAINT ORANGE (-6950 -50);
DISPLAY INVISIBLE (-6950 -50);
FORCEPROP 2 LAST SEC_TYPE 0402
J 0
(-6900 175);
DISPLAY 1.021277 (-6900 175);
PAINT ORANGE (-6900 175);
DISPLAY INVISIBLE (-6900 175);
FORCEPROP 2 LAST SEC 1
J 0
(-6900 175);
DISPLAY 0.680851 (-6900 175);
PAINT MONO (-6900 175);
DISPLAY INVISIBLE (-6900 175);
FORCEPROP 2 LAST CDS_LOCATION R1D18
J 0
(-6905 75);
DISPLAY 0.617021 (-6905 75);
PAINT AQUA (-6905 75);
DISPLAY INVISIBLE (-6905 75);
FORCEPROP 2 LAST ROOM HOT_SWAP
J 0
(-6900 125);
PAINT MONO (-6900 125);
DISPLAY INVISIBLE (-6900 125);
FORCEPROP 1 LAST PATH I87
J 0
(-6900 125);
DISPLAY 0.978723 (-6900 125);
PAINT WHITE (-6900 125);
DISPLAY INVISIBLE (-6900 125);
FORCEADD RES..2
(-6300 -50);
FORCEPROP 1 LASTPIN (-6300 -150) $PN 2
J 0
(-6295 -140);
DISPLAY 0.617021 (-6295 -140);
PAINT ORANGE (-6295 -140);
FORCEPROP 1 LAST WATTAGE 1/16W
J 0
(-6260 -75);
DISPLAY 0.617021 (-6260 -75);
PAINT SKYBLUE (-6260 -75);
FORCEPROP 1 LAST MATERIAL CHIP
J 0
(-6260 -125);
DISPLAY 0.617021 (-6260 -125);
PAINT SKYBLUE (-6260 -125);
FORCEPROP 1 LAST PACK_TYPE 0402
J 0
(-6260 -225);
DISPLAY 0.617021 (-6260 -225);
PAINT SKYBLUE (-6260 -225);
FORCEPROP 1 LAST PART_NUMBER G21796-010
J 0
(-6260 -175);
DISPLAY 0.617021 (-6260 -175);
PAINT BLUE (-6260 -175);
FORCEPROP 1 LAST TOLERANCE 1%
J 0
(-6255 -25);
DISPLAY 0.617021 (-6255 -25);
PAINT SKYBLUE (-6255 -25);
FORCEPROP 1 LASTPIN (-6300 50) $PN 1
J 0
(-6295 12);
DISPLAY 0.617021 (-6295 12);
PAINT ORANGE (-6295 12);
FORCEPROP 1 LAST VALUE 100.0K
J 0
(-6255 25);
DISPLAY 0.617021 (-6255 25);
PAINT SKYBLUE (-6255 25);
FORCEPROP 1 LAST LOCATION R1D11
J 0
(-6255 75);
DISPLAY 0.617021 (-6255 75);
PAINT AQUA (-6255 75);
FORCEPROP 2 LAST CDS_LIB mstr_discrete
J 0
(-6300 -50);
PAINT ORANGE (-6300 -50);
DISPLAY INVISIBLE (-6300 -50);
FORCEPROP 2 LAST ROOM HOT_SWAP
J 0
(-6250 125);
PAINT MONO (-6250 125);
DISPLAY INVISIBLE (-6250 125);
FORCEPROP 1 LAST PATH I88
J 0
(-6250 125);
DISPLAY 0.978723 (-6250 125);
PAINT WHITE (-6250 125);
DISPLAY INVISIBLE (-6250 125);
FORCEPROP 2 LAST CDS_LOCATION R1D11
J 0
(-6255 75);
DISPLAY 0.617021 (-6255 75);
PAINT AQUA (-6255 75);
DISPLAY INVISIBLE (-6255 75);
FORCEPROP 2 LAST SEC 1
J 0
(-6250 175);
DISPLAY 0.680851 (-6250 175);
PAINT MONO (-6250 175);
DISPLAY INVISIBLE (-6250 175);
FORCEPROP 2 LAST SEC_TYPE 0402
J 0
(-6250 175);
DISPLAY 1.021277 (-6250 175);
PAINT ORANGE (-6250 175);
DISPLAY INVISIBLE (-6250 175);
FORCEADD AGND0..1
(-6300 -325);
FORCEPROP 3 LASTPIN (-6300 -275) SIG_NAME AGND_HSC\g
J 0
(-6290 -265);
DISPLAY 0.659574 (-6290 -265);
PAINT MONO (-6290 -265);
DISPLAY INVISIBLE (-6290 -265);
FORCEPROP 1 LAST HDL_POWER AGND_HSC
J 1
(-6300 -375);
DISPLAY 0.617021 (-6300 -375);
PAINT GREEN (-6300 -375);
FORCEPROP 2 LAST ROOM VR_P3V3
J 0
(-6325 -350);
PAINT ORANGE (-6325 -350);
DISPLAY INVISIBLE (-6325 -350);
FORCEPROP 1 LAST PATH I89
J 0
(-6225 -325);
DISPLAY 0.872340 (-6225 -325);
PAINT AQUA (-6225 -325);
DISPLAY INVISIBLE (-6225 -325);
FORCEPROP 1 LAST BODY_TYPE PLUMBING
J 0
(-6345 -368);
DISPLAY 0.340426 (-6345 -368);
PAINT GREEN (-6345 -368);
DISPLAY INVISIBLE (-6345 -368);
FORCEPROP 2 LAST CDS_LIB mstr_symbols
J 0
(-6300 -325);
PAINT ORANGE (-6300 -325);
DISPLAY INVISIBLE (-6300 -325);
FORCEPROP 2 LAST BOM_COST MIO_VRD_MAIN
J 0
(-6275 -350);
PAINT ORANGE (-6275 -350);
DISPLAY INVISIBLE (-6275 -350);
FORCEPROP 1 LAST VOLTAGE 0
J 0
(-6300 -325);
PAINT SKYBLUE (-6300 -325);
DISPLAY INVISIBLE (-6300 -325);
FORCEADD RES..2
(-7200 3625);
FORCEPROP 1 LASTPIN (-7200 3725) $PN 1
J 0
(-7195 3687);
DISPLAY 0.617021 (-7195 3687);
PAINT ORANGE (-7195 3687);
FORCEPROP 1 LASTPIN (-7200 3525) $PN 2
J 0
(-7195 3535);
DISPLAY 0.617021 (-7195 3535);
PAINT ORANGE (-7195 3535);
FORCEPROP 1 LAST PACK_TYPE 0402
J 0
(-7160 3450);
DISPLAY 0.617021 (-7160 3450);
PAINT SKYBLUE (-7160 3450);
FORCEPROP 1 LAST MATERIAL CHIP
J 0
(-7160 3550);
DISPLAY 0.617021 (-7160 3550);
PAINT SKYBLUE (-7160 3550);
FORCEPROP 1 LAST PART_NUMBER G21796-177
J 0
(-7160 3500);
DISPLAY 0.617021 (-7160 3500);
PAINT BLUE (-7160 3500);
FORCEPROP 1 LAST LOCATION R1D43
J 0
(-7155 3750);
DISPLAY 0.617021 (-7155 3750);
PAINT AQUA (-7155 3750);
FORCEPROP 1 LAST VALUE 7.5K
J 0
(-7155 3700);
DISPLAY 0.617021 (-7155 3700);
PAINT SKYBLUE (-7155 3700);
FORCEPROP 1 LAST TOLERANCE 1%
J 0
(-7155 3650);
DISPLAY 0.617021 (-7155 3650);
PAINT SKYBLUE (-7155 3650);
FORCEPROP 1 LAST WATTAGE 1/16W
J 0
(-7160 3600);
DISPLAY 0.617021 (-7160 3600);
PAINT SKYBLUE (-7160 3600);
FORCEPROP 2 LAST CDS_LIB mstr_discrete
J 0
(-7200 3625);
PAINT ORANGE (-7200 3625);
DISPLAY INVISIBLE (-7200 3625);
FORCEPROP 0 LAST ROOM HOT_SWAP
J 0
(-7150 3800);
DISPLAY 1.021277 (-7150 3800);
PAINT ORANGE (-7150 3800);
DISPLAY INVISIBLE (-7150 3800);
FORCEPROP 1 LAST PATH I9
J 0
(-7150 3800);
DISPLAY 0.978723 (-7150 3800);
PAINT WHITE (-7150 3800);
DISPLAY INVISIBLE (-7150 3800);
FORCEPROP 2 LAST CDS_LOCATION R1D43
J 0
(-7155 3750);
DISPLAY 0.617021 (-7155 3750);
PAINT AQUA (-7155 3750);
DISPLAY INVISIBLE (-7155 3750);
FORCEPROP 2 LAST SEC 1
J 0
(-7150 3850);
DISPLAY 0.680851 (-7150 3850);
PAINT MONO (-7150 3850);
DISPLAY INVISIBLE (-7150 3850);
FORCEPROP 2 LAST SEC_TYPE 0402
J 0
(-7150 3850);
DISPLAY 1.021277 (-7150 3850);
PAINT ORANGE (-7150 3850);
DISPLAY INVISIBLE (-7150 3850);
FORCEADD P12V_PSU..1
(-7300 950);
FORCEPROP 3 LASTPIN (-7300 900) SIG_NAME P12V_PSU\g
J 0
(-7290 910);
DISPLAY 0.659574 (-7290 910);
PAINT MONO (-7290 910);
DISPLAY INVISIBLE (-7290 910);
FORCEPROP 1 LAST BODY_TYPE PLUMBING
J 0
(-7345 907);
DISPLAY 0.340426 (-7345 907);
PAINT GREEN (-7345 907);
DISPLAY INVISIBLE (-7345 907);
FORCEPROP 2 LAST CDS_LIB mstr_symbols
J 0
(-7300 950);
PAINT ORANGE (-7300 950);
DISPLAY INVISIBLE (-7300 950);
FORCEPROP 1 LAST VOLTAGE 12.0
J 0
(-7345 907);
DISPLAY 0.340426 (-7345 907);
PAINT SKYBLUE (-7345 907);
DISPLAY INVISIBLE (-7345 907);
FORCEPROP 1 LAST PATH I90
J 0
(-7250 975);
DISPLAY 0.872340 (-7250 975);
PAINT AQUA (-7250 975);
DISPLAY INVISIBLE (-7250 975);
FORCEPROP 1 LAST HDL_POWER P12V_PSU
J 1
(-7300 1000);
DISPLAY 0.872340 (-7300 1000);
PAINT GREEN (-7300 1000);
DISPLAY INVISIBLE (-7300 1000);
FORCEPROP 2 LAST BOM_COST NT_BASE_VRD
J 0
(-7300 1050);
DISPLAY 0.617021 (-7300 1050);
PAINT ORANGE (-7300 1050);
DISPLAY INVISIBLE (-7300 1050);
FORCEPROP 2 LAST ROOM P2V5_LAN_AUX_VR
J 0
(-7300 1050);
DISPLAY 0.617021 (-7300 1050);
PAINT ORANGE (-7300 1050);
DISPLAY INVISIBLE (-7300 1050);
FORCEADD RES..2
(-7300 750);
FORCEPROP 1 LASTPIN (-7300 650) $PN 2
J 0
(-7295 660);
DISPLAY 0.617021 (-7295 660);
PAINT ORANGE (-7295 660);
FORCEPROP 1 LAST TOLERANCE 1%
J 0
(-7255 775);
DISPLAY 0.617021 (-7255 775);
PAINT SKYBLUE (-7255 775);
FORCEPROP 1 LASTPIN (-7300 850) $PN 1
J 0
(-7295 812);
DISPLAY 0.617021 (-7295 812);
PAINT ORANGE (-7295 812);
FORCEPROP 1 LAST WATTAGE 1/16W
J 0
(-7260 725);
DISPLAY 0.617021 (-7260 725);
PAINT SKYBLUE (-7260 725);
FORCEPROP 1 LAST MATERIAL CHIP
J 0
(-7260 675);
DISPLAY 0.617021 (-7260 675);
PAINT SKYBLUE (-7260 675);
FORCEPROP 1 LAST PACK_TYPE 0402
J 0
(-7250 575);
DISPLAY 0.617021 (-7250 575);
PAINT SKYBLUE (-7250 575);
FORCEPROP 1 LAST VALUE 100.0K
J 0
(-7255 825);
DISPLAY 0.617021 (-7255 825);
PAINT SKYBLUE (-7255 825);
FORCEPROP 1 LAST PART_NUMBER G21796-010
J 0
(-7250 625);
DISPLAY 0.617021 (-7250 625);
PAINT BLUE (-7250 625);
FORCEPROP 1 LAST LOCATION R1D15
J 0
(-7255 875);
DISPLAY 0.617021 (-7255 875);
PAINT AQUA (-7255 875);
FORCEPROP 2 LAST CDS_LIB mstr_discrete
J 0
(-7300 750);
PAINT ORANGE (-7300 750);
DISPLAY INVISIBLE (-7300 750);
FORCEPROP 2 LAST SEC_TYPE 0402
J 0
(-7250 975);
DISPLAY 1.021277 (-7250 975);
PAINT ORANGE (-7250 975);
DISPLAY INVISIBLE (-7250 975);
FORCEPROP 2 LAST SEC 1
J 0
(-7250 975);
DISPLAY 0.680851 (-7250 975);
PAINT MONO (-7250 975);
DISPLAY INVISIBLE (-7250 975);
FORCEPROP 2 LAST CDS_LOCATION R1D15
J 0
(-7255 875);
DISPLAY 0.617021 (-7255 875);
PAINT AQUA (-7255 875);
DISPLAY INVISIBLE (-7255 875);
FORCEPROP 1 LAST PATH I92
J 0
(-7250 925);
DISPLAY 0.978723 (-7250 925);
PAINT WHITE (-7250 925);
DISPLAY INVISIBLE (-7250 925);
FORCEPROP 2 LAST ROOM HOT_SWAP
J 0
(-7250 925);
PAINT MONO (-7250 925);
DISPLAY INVISIBLE (-7250 925);
FORCEADD OFFPAGE..2
R 2
(-5800 2825);
FORCEPROP 2 LAST $XR0 200 
J 0
(-6055 2825);
DISPLAY 0.638298 (-6055 2825);
PAINT MONO (-6055 2825);
FORCEPROP 1 LAST OFFPAGE TRUE
J 2
(-6125 2700);
DISPLAY 0.872340 (-6125 2700);
PAINT GREEN (-6125 2700);
DISPLAY INVISIBLE (-6125 2700);
FORCEPROP 1 LAST COMMENT_BODY TRUE
J 2
(-5755 2730);
DISPLAY 0.872340 (-5755 2730);
PAINT GREEN (-5755 2730);
DISPLAY INVISIBLE (-5755 2730);
FORCEPROP 2 LAST CDS_LIB mstr_standard
J 0
(-5800 2825);
PAINT MONO (-5800 2825);
DISPLAY INVISIBLE (-5800 2825);
FORCEPROP 2 LAST PATH I98
J 0
(-5750 2900);
DISPLAY 1.021277 (-5750 2900);
PAINT ORANGE (-5750 2900);
DISPLAY INVISIBLE (-5750 2900);
FORCEADD ZENER..4
(-5100 3875);
FORCEPROP 1 LAST PACK_TYPE SM
J 0
(-4975 3800);
DISPLAY 0.617021 (-4975 3800);
PAINT SKYBLUE (-4975 3800);
FORCEPROP 1 LASTPIN (-5100 3775) $PN 2
J 0
(-5080 3780);
DISPLAY 0.617021 (-5080 3780);
PAINT AQUA (-5080 3780);
FORCEPROP 1 LASTPIN (-5100 4025) $PN 1
J 0
(-5080 3995);
DISPLAY 0.617021 (-5080 3995);
PAINT AQUA (-5080 3995);
FORCEPROP 1 LAST MATERIAL IC
J 0
(-4975 3850);
DISPLAY 0.617021 (-4975 3850);
PAINT SKYBLUE (-4975 3850);
FORCEPROP 1 LAST VALUE 13V
J 0
(-4975 3900);
DISPLAY 0.617021 (-4975 3900);
PAINT SKYBLUE (-4975 3900);
FORCEPROP 1 LAST LOCATION VR1D1
J 0
(-4975 3950);
DISPLAY 0.617021 (-4975 3950);
PAINT AQUA (-4975 3950);
FORCEPROP 1 LAST PART_NUMBER H69095-001
J 0
(-4975 3750);
DISPLAY 0.617021 (-4975 3750);
PAINT BLUE (-4975 3750);
FORCEPROP 1 LAST PATH I99
J 0
(-4975 4000);
DISPLAY 0.978723 (-4975 4000);
PAINT BLUE (-4975 4000);
DISPLAY INVISIBLE (-4975 4000);
FORCEPROP 2 LAST CDS_LOCATION VR1D1
J 0
(-4975 3950);
DISPLAY 0.617021 (-4975 3950);
PAINT AQUA (-4975 3950);
DISPLAY INVISIBLE (-4975 3950);
FORCEPROP 2 LAST SEC 1
J 0
(-4975 4050);
PAINT MONO (-4975 4050);
DISPLAY INVISIBLE (-4975 4050);
FORCEPROP 2 LAST CDS_LIB mstr_discrete
J 0
(-5100 3875);
PAINT MONO (-5100 3875);
DISPLAY INVISIBLE (-5100 3875);
FORCEPROP 2 LAST SEC_TYPE SM
J 0
(-4975 4050);
DISPLAY 1.021277 (-4975 4050);
PAINT ORANGE (-4975 4050);
DISPLAY INVISIBLE (-4975 4050);
FORCEADD DESIGN_NOTE..1
(-4375 725);
FORCEPROP 2 LAST ROOM BMC
J 0
(-4575 675);
PAINT WHITE (-4575 675);
DISPLAY INVISIBLE (-4575 675);
FORCEPROP 2 LAST CDS_LIB mstr_symbols
J 0
(-4375 725);
PAINT ORANGE (-4375 725);
DISPLAY INVISIBLE (-4375 725);
FORCEPROP 2 LAST BOM_COST SM_CONTROLLER
J 0
(-4575 675);
PAINT WHITE (-4575 675);
DISPLAY INVISIBLE (-4575 675);
FORCEPROP 1 LAST COMMENT_BODY TRUE
J 0
(-4350 825);
DISPLAY 1.319149 (-4350 825);
PAINT WHITE (-4350 825);
DISPLAY INVISIBLE (-4350 825);
FORCEADD DNS..2
(-395 2620);
PAINT RED (-395 2620);
FORCEPROP 1 LAST COMMENT_BODY TRUE
R 1
J 0
(-320 2395);
DISPLAY 0.872340 (-320 2395);
PAINT GREEN (-320 2395);
DISPLAY INVISIBLE (-320 2395);
FORCEPROP 2 LAST CDS_LIB mstr_misc
J 0
(-395 2620);
PAINT ORANGE (-395 2620);
DISPLAY INVISIBLE (-395 2620);
FORCEADD DNS..1
(-7745 670);
PAINT RED (-7745 670);
FORCEPROP 1 LAST COMMENT_BODY TRUE
R 1
J 0
(-7670 445);
DISPLAY 0.872340 (-7670 445);
PAINT GREEN (-7670 445);
DISPLAY INVISIBLE (-7670 445);
FORCEPROP 2 LAST CDS_LIB mstr_misc
J 0
(-7745 670);
PAINT ORANGE (-7745 670);
DISPLAY INVISIBLE (-7745 670);
FORCEADD DNS..2
(-7670 2845);
PAINT RED (-7670 2845);
FORCEPROP 1 LAST COMMENT_BODY TRUE
R 1
J 0
(-7595 2620);
DISPLAY 0.872340 (-7595 2620);
PAINT GREEN (-7595 2620);
DISPLAY INVISIBLE (-7595 2620);
FORCEPROP 2 LAST CDS_LIB mstr_misc
J 0
(-7670 2845);
PAINT ORANGE (-7670 2845);
DISPLAY INVISIBLE (-7670 2845);
FORCEADD DNS..2
(-4620 1020);
PAINT RED (-4620 1020);
FORCEPROP 1 LAST COMMENT_BODY TRUE
R 1
J 0
(-4545 795);
DISPLAY 0.872340 (-4545 795);
PAINT GREEN (-4545 795);
DISPLAY INVISIBLE (-4545 795);
FORCEPROP 2 LAST CDS_LIB mstr_misc
J 0
(-4620 1020);
PAINT ORANGE (-4620 1020);
DISPLAY INVISIBLE (-4620 1020);
FORCEADD DESIGN_NOTE..1
(-7825 1675);
FORCEPROP 0 LAST L3 POWER CONNECTOR
J 0
(-8025 1400);
DISPLAY 0.808511 (-8025 1400);
PAINT ORANGE (-8025 1400);
FORCEPROP 0 LAST L2 TO BE USED WHEN USING TYCO
J 0
(-8025 1475);
DISPLAY 0.808511 (-8025 1475);
PAINT ORANGE (-8025 1475);
FORCEPROP 0 LAST L1 D53458-001 EMPTY LOCATION
J 0
(-8025 1550);
DISPLAY 0.808511 (-8025 1550);
PAINT ORANGE (-8025 1550);
FORCEPROP 2 LAST CDS_LIB mstr_symbols
J 0
(-7825 1675);
PAINT ORANGE (-7825 1675);
DISPLAY INVISIBLE (-7825 1675);
FORCEPROP 1 LAST COMMENT_BODY TRUE
J 0
(-7800 1775);
DISPLAY 0.978723 (-7800 1775);
PAINT ORANGE (-7800 1775);
DISPLAY INVISIBLE (-7800 1775);
FORCEADD DNS..2
(-7995 2820);
PAINT RED (-7995 2820);
FORCEPROP 1 LAST COMMENT_BODY TRUE
R 1
J 0
(-7920 2595);
DISPLAY 0.872340 (-7920 2595);
PAINT GREEN (-7920 2595);
DISPLAY INVISIBLE (-7920 2595);
FORCEPROP 2 LAST CDS_LIB mstr_misc
J 0
(-7995 2820);
PAINT ORANGE (-7995 2820);
DISPLAY INVISIBLE (-7995 2820);
FORCEADD INTEL_CORP_BPAGE..1
(-100 -425);
FORCEPROP 1 LAST CDS_CON_LAST_MODIFIED Tue Dec 01 11:52:20 2015
J 0
(-1525 -100);
PAINT GREEN (-1525 -100);
DISPLAY INVISIBLE (-1525 -100);
FORCEPROP 1 LAST CUSTOM_TXT_CDS <CURRENT_DESIGN_SHEET> OF <TOTAL_DESIGN_SHEETS>
J 0
(-600 -400);
PAINT GREEN (-600 -400);
FORCEPROP 1 LAST CUSTOM_TXT_CDS <CON_LAST_MODIFIED>
J 0
(-2025 -75);
PAINT GREEN (-2025 -75);
FORCEPROP 2 LAST CUSTOM_TXT_CDS <XR_PAGE_TITLE>
J 0
(-7990 4825);
DISPLAY 0.638298 (-7990 4825);
PAINT PINK (-7990 4825);
DISPLAY INVISIBLE (-7990 4825);
FORCEPROP 1 LAST SCH_TITLE HOT SWAP CONTROLLER (1/2)
J 0
(-7950 -300);
DISPLAY 1.212766 (-7950 -300);
PAINT ORANGE (-7950 -300);
FORCEPROP 1 LAST SCH_ADDRESS1 2200 Mission College Blvd.
J 0
(-4075 -300);
DISPLAY 0.617021 (-4075 -300);
PAINT GREEN (-4075 -300);
FORCEPROP 1 LAST SCH_ADDRESS2 P.O. BOX 58119
J 0
(-4075 -350);
DISPLAY 0.617021 (-4075 -350);
PAINT GREEN (-4075 -350);
FORCEPROP 1 LAST SCH_ADDRESS3 Santa Clara, CA 95052-8119
J 0
(-4075 -400);
DISPLAY 0.617021 (-4075 -400);
PAINT GREEN (-4075 -400);
FORCEPROP 1 LAST SCH_NUMBER H4694802
J 0
(-1400 -275);
DISPLAY 1.212766 (-1400 -275);
PAINT YELLOW (-1400 -275);
FORCEPROP 1 LAST SCH_DEPT BESD
J 1
(-4550 -325);
DISPLAY 1.212766 (-4550 -325);
PAINT YELLOW (-4550 -325);
FORCEPROP 1 LAST SCH_REV 2.420
J 0
(-350 -275);
DISPLAY 0.978723 (-350 -275);
PAINT YELLOW (-350 -275);
FORCEPROP 1 LAST COMMENT_BODY TRUE
J 0
(-88 -413);
DISPLAY 0.468085 (-88 -413);
PAINT GREEN (-88 -413);
DISPLAY INVISIBLE (-88 -413);
FORCEPROP 2 LAST CDS_LIB mstr_symbols
J 0
(-100 -425);
PAINT ORANGE (-100 -425);
DISPLAY INVISIBLE (-100 -425);
FORCEPROP 2 LAST PAGE_BORDER TRUE
J 0
(-7990 4825);
DISPLAY 0.851064 (-7990 4825);
PAINT PINK (-7990 4825);
DISPLAY INVISIBLE (-7990 4825);
FORCEPROP 2 LAST CDS_XR_PAGE_TITLE CR-199 : @BASEBOARD_FAB2_LIB.BASEBOARD_FAB2(SCH_1):PAGE199
J 0
(-7990 4825);
DISPLAY 0.638298 (-7990 4825);
PAINT PINK (-7990 4825);
DISPLAY INVISIBLE (-7990 4825);
WIRE 16 -1 (-5300 700)(-5300 575);
WIRE 16 -1 (-5300 575)(-5400 575);
WIRE 16 -1 (-5400 575)(-5600 575);
WIRE 16 -1 (-5400 575)(-5400 500);
WIRE 16 -1 (-5600 650)(-5600 575);
WIRE 16 -1 (-6150 650)(-6150 750);
WIRE 16 -1 (-2500 2525)(-2150 2525);
WIRE 16 -1 (-2150 2325)(-2150 2525);
WIRE 16 -1 (-6600 25)(-6600 200);
WIRE 16 -1 (-6775 3475)(-6775 3325);
WIRE 16 -1 (-6775 3325)(-7200 3325);
WIRE 16 -1 (-7200 3525)(-7200 3325);
WIRE 16 -1 (-7200 3300)(-7200 3325);
WIRE 16 -1 (-5525 3400)(-5525 3500);
WIRE 16 -1 (-5100 3775)(-5100 3450);
WIRE 16 -1 (-6075 3475)(-6075 3350);
WIRE 16 -1 (-6375 3350)(-6075 3350);
WIRE 16 -1 (-6500 3350)(-6375 3350);
WIRE 16 -1 (-6375 3350)(-6375 3325);
WIRE 16 -1 (-6500 3500)(-6500 3350);
WIRE 16 -1 (-2500 2425)(-2375 2425);
WIRE 16 -1 (-2375 2425)(-2375 2350);
WIRE 16 -1 (-5650 1900)(-5650 1850);
WIRE 16 -1 (-5000 150)(-5000 325);
WIRE 16 -1 (-2750 200)(-2750 300);
WIRE 16 -1 (-2750 300)(-2925 300);
WIRE 16 -1 (-3125 300)(-3300 300);
WIRE 16 -1 (-3300 300)(-3300 200);
WIRE 16 -1 (-2500 2625)(-2000 2625);
WIRE 16 -1 (-2000 2625)(-2000 2425);
WIRE 16 -1 (-4850 1400)(-4850 750);
WIRE 16 -1 (-4850 750)(-4725 750);
WIRE 16 -1 (-4625 750)(-4725 750);
WIRE 16 -1 (-4725 750)(-4725 675);
WIRE 16 -1 (-4625 925)(-4625 750);
WIRE 16 -1 (-8000 2225)(-7675 2225);
WIRE 16 -1 (-8000 2225)(-8000 2275);
WIRE 16 -1 (-7675 2275)(-7675 2225);
WIRE 16 -1 (-7675 2125)(-7675 2225);
WIRE 16 -1 (-2825 650)(-2825 600);
WIRE 16 -1 (-7025 2075)(-7025 2025);
WIRE 16 -1 (-6725 1625)(-6725 1575);
WIRE 16 -1 (-1600 1550)(-1600 1500);
WIRE 16 -1 (-400 2525)(-400 2450);
WIRE 16 -1 (-400 3125)(-400 3550);
WIRE 16 -1 (-6725 2125)(-6725 2200);
WIRE 16 -1 (-3125 1175)(-3125 1225);
WIRE 16 -1 (-5525 4225)(-5100 4225);
WIRE 16 -1 (-5525 4125)(-5525 4225);
WIRE 16 -1 (-5525 4225)(-6500 4225);
WIRE 16 -1 (-5100 4225)(-5100 4025);
WIRE 16 -1 (-6500 4150)(-6500 4225);
WIRE 16 -1 (-6675 4225)(-6500 4225);
WIRE 16 -1 (-7200 4225)(-6675 4225);
WIRE 16 -1 (-6675 4375)(-6675 4225);
WIRE 16 -1 (-7200 4125)(-7200 4225);
WIRE 16 -1 (-5875 25)(-5875 75);
WIRE 16 -1 (-6950 -150)(-6950 -225);
WIRE 16 -1 (-6950 -225)(-6300 -225);
WIRE 16 -1 (-6300 -225)(-6300 -150);
WIRE 16 -1 (-6300 -225)(-6300 -275);
WIRE 16 -1 (-7300 850)(-7300 900);
WIRE 16 -1 (-7025 2325)(-6725 2325);
WIRE 16 -1 (-7025 2325)(-7025 2275);
WIRE 16 -1 (-4000 2325)(-6725 2325);
WIRE 16 -1 (-6725 2450)(-6725 2325);
WIRE 16 -1 (-7175 2450)(-6725 2450);
FORCEPROP 0 LAST SIG_NAME FM_P12V_HOTSWAP0_EN
J 0
(-7160 2460);
DISPLAY 0.617021 (-7160 2460);
PAINT ORANGE (-7160 2460);
WIRE 16 -1 (-400 2825)(-400 2925);
WIRE 16 -1 (-400 2825)(-400 2725);
WIRE 16 -1 (-2500 2825)(-400 2825);
FORCEPROP 0 LAST SIG_NAME A_HSC_VOUT
J 0
(-1335 2835);
DISPLAY 0.617021 (-1335 2835);
PAINT ORANGE (-1335 2835);
FORCEPROP 2 LASTPROP $XRERR UNIQUE?
J 0
(-1575 2835);
DISPLAY 0.638298 (-1575 2835);
PAINT MONO (-1575 2835);
DISPLAY INVISIBLE (-1575 2835);
WIRE 16 -1 (-875 3950)(-1600 3950);
FORCEPROP 0 LAST SIG_NAME IRQ_SML1_PMBUS_ALERT_N
J 0
(-1535 3960);
DISPLAY 0.617021 (-1535 3960);
PAINT ORANGE (-1535 3960);
WIRE 16 -1 (-800 925)(-1950 925);
FORCEPROP 0 LAST SIG_NAME PWRGD_P12V_HSC
J 0
(-1685 935);
DISPLAY 0.617021 (-1685 935);
PAINT ORANGE (-1685 935);
WIRE 16 -1 (-1950 1375)(-800 1375);
FORCEPROP 0 LAST SIG_NAME IRQ_HSC_FAULT_N
J 0
(-1285 1385);
DISPLAY 0.617021 (-1285 1385);
PAINT ORANGE (-1285 1385);
WIRE 16 -1 (-1600 1750)(-1600 1825);
WIRE 16 -1 (-1600 1825)(-1825 1825);
WIRE 16 -1 (-1825 1825)(-1825 1650);
WIRE 16 -1 (-1825 1650)(-1750 1650);
WIRE 16 -1 (-1825 1425)(-1825 1650);
WIRE 16 -1 (-4275 1425)(-1825 1425);
FORCEPROP 0 LAST SIG_NAME A_HSC_TEMP
J 0
(-3610 1435);
DISPLAY 0.617021 (-3610 1435);
PAINT ORANGE (-3610 1435);
FORCEPROP 2 LASTPROP $XRERR UNIQUE?
J 0
(-3850 1435);
DISPLAY 0.638298 (-3850 1435);
PAINT MONO (-3850 1435);
DISPLAY INVISIBLE (-3850 1435);
WIRE 16 -1 (-4275 2175)(-4275 1425);
WIRE 16 -1 (-4000 2175)(-4275 2175);
WIRE 16 -1 (-2175 2025)(-825 2025);
FORCEPROP 0 LAST SIG_NAME A_HSC_MOP
J 0
(-1435 2035);
DISPLAY 0.617021 (-1435 2035);
PAINT ORANGE (-1435 2035);
WIRE 16 -1 (-2175 1575)(-2175 2025);
WIRE 16 -1 (-4125 1575)(-2175 1575);
WIRE 16 -1 (-4125 1925)(-4125 1575);
WIRE 16 -1 (-4000 1925)(-4125 1925);
WIRE 16 -1 (-2125 1975)(-825 1975);
FORCEPROP 0 LAST SIG_NAME A_HSC_HSN
J 0
(-1435 1985);
DISPLAY 0.617021 (-1435 1985);
PAINT ORANGE (-1435 1985);
WIRE 16 -1 (-2125 1525)(-2125 1975);
WIRE 16 -1 (-4175 1525)(-2125 1525);
WIRE 16 -1 (-4175 2025)(-4175 1525);
WIRE 16 -1 (-4000 2025)(-4175 2025);
WIRE 16 -1 (-2075 1925)(-825 1925);
FORCEPROP 0 LAST SIG_NAME A_HSC_HSP
J 0
(-1435 1935);
DISPLAY 0.617021 (-1435 1935);
PAINT ORANGE (-1435 1935);
WIRE 16 -1 (-2075 1475)(-2075 1925);
WIRE 16 -1 (-4225 1475)(-2075 1475);
WIRE 16 -1 (-4225 2075)(-4225 1475);
WIRE 16 -1 (-4000 2075)(-4225 2075);
WIRE 16 -1 (-2225 2075)(-825 2075);
FORCEPROP 0 LAST SIG_NAME A_HSC_MON
J 0
(-1435 2085);
DISPLAY 0.617021 (-1435 2085);
PAINT ORANGE (-1435 2085);
WIRE 16 -1 (-2225 1625)(-2225 2075);
WIRE 16 -1 (-4075 1625)(-2225 1625);
WIRE 16 -1 (-4075 1875)(-4075 1625);
WIRE 16 -1 (-4000 1875)(-4075 1875);
WIRE 16 -1 (-2500 3225)(-1975 3225);
FORCEPROP 0 LAST SIG_NAME TP_HSC_ALERT2_N
J 0
(-2410 3235);
DISPLAY 0.617021 (-2410 3235);
PAINT ORANGE (-2410 3235);
FORCEPROP 2 LASTPROP $XRERR UNIQUE?
J 0
(-1945 3225);
DISPLAY 0.638298 (-1945 3225);
PAINT MONO (-1945 3225);
DISPLAY INVISIBLE (-1945 3225);
WIRE 16 -1 (-2500 3125)(-1975 3125);
FORCEPROP 0 LAST SIG_NAME TP_HSC_MCLK
J 0
(-2410 3135);
DISPLAY 0.617021 (-2410 3135);
PAINT ORANGE (-2410 3135);
FORCEPROP 2 LASTPROP $XRERR UNIQUE?
J 0
(-1945 3125);
DISPLAY 0.638298 (-1945 3125);
PAINT MONO (-1945 3125);
DISPLAY INVISIBLE (-1945 3125);
WIRE 16 -1 (-2500 3025)(-1975 3025);
FORCEPROP 0 LAST SIG_NAME TP_HSC_MDAT
J 0
(-2410 3035);
DISPLAY 0.617021 (-2410 3035);
PAINT ORANGE (-2410 3035);
FORCEPROP 2 LASTPROP $XRERR UNIQUE?
J 0
(-1945 3025);
DISPLAY 0.638298 (-1945 3025);
PAINT MONO (-1945 3025);
DISPLAY INVISIBLE (-1945 3025);
WIRE 16 -1 (-875 3275)(-2500 3275);
FORCEPROP 0 LAST SIG_NAME IRQ_SML1_PMBUS_ALERT_R_N
J 0
(-2410 3285);
DISPLAY 0.617021 (-2410 3285);
PAINT ORANGE (-2410 3285);
WIRE 16 -1 (-1800 3950)(-2575 3950);
FORCEPROP 0 LAST SIG_NAME IRQ_SML1_PMBUS_ALERT_R_N
J 0
(-2510 3960);
DISPLAY 0.617021 (-2510 3960);
PAINT ORANGE (-2510 3960);
WIRE 16 -1 (-2500 2925)(-875 2925);
FORCEPROP 0 LAST SIG_NAME A_HSC_CSOUT
J 0
(-1335 2935);
DISPLAY 0.617021 (-1335 2935);
PAINT ORANGE (-1335 2935);
WIRE 16 -1 (-2500 2725)(-875 2725);
FORCEPROP 0 LAST SIG_NAME A_HSC_GATE
J 0
(-1335 2735);
DISPLAY 0.617021 (-1335 2735);
PAINT ORANGE (-1335 2735);
WIRE 16 -1 (-2150 925)(-2825 925);
WIRE 16 -1 (-2825 925)(-2825 850);
WIRE 16 -1 (-2825 925)(-3125 925);
WIRE 16 -1 (-3125 975)(-3125 925);
WIRE 16 -1 (-4375 925)(-3125 925);
FORCEPROP 0 LAST SIG_NAME PWRGD_P12V_R
J 0
(-3760 935);
DISPLAY 0.617021 (-3760 935);
PAINT ORANGE (-3760 935);
FORCEPROP 2 LASTPROP $XRERR UNIQUE?
J 0
(-4000 935);
DISPLAY 0.638298 (-4000 935);
PAINT MONO (-4000 935);
DISPLAY INVISIBLE (-4000 935);
WIRE 16 -1 (-4375 2425)(-4375 925);
WIRE 16 -1 (-4000 2425)(-4375 2425);
WIRE 16 -1 (-4000 2975)(-5050 2975);
FORCEPROP 0 LAST SIG_NAME A_HSC_ISET
J 0
(-4610 2985);
DISPLAY 0.617021 (-4610 2985);
PAINT ORANGE (-4610 2985);
FORCEPROP 2 LASTPROP $XRERR UNIQUE?
J 0
(-4850 2985);
DISPLAY 0.638298 (-4850 2985);
PAINT MONO (-4850 2985);
DISPLAY INVISIBLE (-4850 2985);
WIRE 16 -1 (-5050 2975)(-5050 1150);
WIRE 16 -1 (-5050 1150)(-6600 1150);
WIRE 16 -1 (-6600 1150)(-6600 1350);
WIRE 16 -1 (-6600 1100)(-6600 1150);
WIRE 16 -1 (-6600 1100)(-6150 1100);
WIRE 16 -1 (-6600 1025)(-6600 1100);
WIRE 16 -1 (-5875 1100)(-6150 1100);
WIRE 16 -1 (-6150 950)(-6150 1100);
WIRE 16 -1 (-5875 975)(-5875 1100);
WIRE 16 -1 (-8000 2925)(-8000 2975);
WIRE 16 -1 (-8000 2975)(-7825 2975);
WIRE 16 -1 (-7825 3175)(-7825 2975);
WIRE 16 -1 (-7825 2975)(-7675 2975);
WIRE 16 -1 (-7675 2950)(-7675 2975);
WIRE 16 -1 (-7825 3175)(-5100 3175);
WIRE 16 -1 (-4000 3175)(-5100 3175);
FORCEPROP 0 LAST SIG_NAME A_HSC_VCAP
J 0
(-4635 3185);
DISPLAY 0.617021 (-4635 3185);
PAINT ORANGE (-4635 3185);
FORCEPROP 2 LASTPROP $XRERR UNIQUE?
J 0
(-4875 3185);
DISPLAY 0.638298 (-4875 3185);
PAINT MONO (-4875 3185);
DISPLAY INVISIBLE (-4875 3185);
WIRE 16 -1 (-5100 2150)(-5100 3175);
WIRE 16 -1 (-5650 2150)(-5100 2150);
WIRE 16 -1 (-5100 1700)(-5100 2150);
WIRE 16 -1 (-5100 1700)(-5300 1700);
WIRE 16 -1 (-5650 2100)(-5650 2150);
WIRE 16 -1 (-5300 1700)(-5600 1700);
WIRE 16 -1 (-5300 1525)(-5300 1700);
WIRE 16 -1 (-5600 1500)(-5600 1700);
WIRE 16 -1 (-6600 1700)(-5600 1700);
WIRE 16 -1 (-6600 1550)(-6600 1700);
WIRE 16 -1 (-6700 3075)(-4000 3075);
FORCEPROP 0 LAST SIG_NAME A_HSC_OV
J 0
(-4635 3085);
DISPLAY 0.617021 (-4635 3085);
PAINT ORANGE (-4635 3085);
FORCEPROP 2 LASTPROP $XRERR UNIQUE?
J 0
(-4875 3085);
DISPLAY 0.638298 (-4875 3085);
PAINT MONO (-4875 3085);
DISPLAY INVISIBLE (-4875 3085);
WIRE 16 -1 (-6700 3800)(-6700 3075);
WIRE 16 -1 (-6700 3800)(-6775 3800);
WIRE 16 -1 (-6775 3800)(-6775 3675);
WIRE 16 -1 (-7200 3800)(-6775 3800);
WIRE 16 -1 (-7200 3925)(-7200 3800);
WIRE 16 -1 (-7200 3725)(-7200 3800);
WIRE 16 -1 (-4000 3125)(-6000 3125);
FORCEPROP 0 LAST SIG_NAME A_HSC_UV
J 0
(-4635 3135);
DISPLAY 0.617021 (-4635 3135);
PAINT ORANGE (-4635 3135);
FORCEPROP 2 LASTPROP $XRERR UNIQUE?
J 0
(-4875 3135);
DISPLAY 0.638298 (-4875 3135);
PAINT MONO (-4875 3135);
DISPLAY INVISIBLE (-4875 3135);
WIRE 16 -1 (-6000 3800)(-6000 3125);
WIRE 16 -1 (-6000 3800)(-6075 3800);
WIRE 16 -1 (-6075 3675)(-6075 3800);
WIRE 16 -1 (-6075 3800)(-6500 3800);
WIRE 16 -1 (-6500 3950)(-6500 3800);
WIRE 16 -1 (-6500 3800)(-6500 3700);
WIRE 16 -1 (-4000 2225)(-5925 2225);
WIRE 16 -1 (-5925 1875)(-5925 2225);
WIRE 16 -1 (-5925 1875)(-6725 1875);
FORCEPROP 0 LAST SIG_NAME A_HSC_PWGIN
J 0
(-6335 1885);
DISPLAY 0.617021 (-6335 1885);
PAINT ORANGE (-6335 1885);
FORCEPROP 2 LASTPROP $XRERR UNIQUE?
J 0
(-6575 1885);
DISPLAY 0.638298 (-6575 1885);
PAINT MONO (-6575 1885);
DISPLAY INVISIBLE (-6575 1885);
WIRE 16 -1 (-6725 1925)(-6725 1875);
WIRE 16 -1 (-6725 1875)(-6725 1825);
WIRE 16 -1 (-4000 2925)(-5000 2925);
FORCEPROP 0 LAST SIG_NAME A_HSC_PSET
J 0
(-4635 2935);
DISPLAY 0.617021 (-4635 2935);
PAINT ORANGE (-4635 2935);
FORCEPROP 2 LASTPROP $XRERR UNIQUE?
J 0
(-4875 2935);
DISPLAY 0.638298 (-4875 2935);
PAINT MONO (-4875 2935);
DISPLAY INVISIBLE (-4875 2935);
WIRE 16 -1 (-5000 2925)(-5000 1050);
WIRE 16 -1 (-5000 525)(-5000 1050);
WIRE 16 -1 (-5000 1050)(-5300 1050);
WIRE 16 -1 (-5300 1050)(-5300 1325);
WIRE 16 -1 (-5300 900)(-5300 1050);
WIRE 16 -1 (-4000 2875)(-4925 2875);
FORCEPROP 0 LAST SIG_NAME A_HSC_ISTART
J 0
(-4635 2885);
DISPLAY 0.617021 (-4635 2885);
PAINT ORANGE (-4635 2885);
FORCEPROP 2 LASTPROP $XRERR UNIQUE?
J 0
(-4875 2885);
DISPLAY 0.638298 (-4875 2885);
PAINT MONO (-4875 2885);
DISPLAY INVISIBLE (-4875 2885);
WIRE 16 -1 (-4925 2875)(-4925 975);
WIRE 16 -1 (-4925 975)(-5600 975);
WIRE 16 -1 (-5600 975)(-5600 1300);
WIRE 16 -1 (-5600 850)(-5600 975);
WIRE 16 -1 (-4000 3275)(-5650 3275);
FORCEPROP 0 LAST VOLTAGE +12V
J 0
(-4625 3350);
DISPLAY 1.021277 (-4625 3350);
PAINT SKYBLUE (-4625 3350);
DISPLAY INVISIBLE (-4625 3350);
FORCEPROP 0 LAST SIG_NAME P12V_HSC_VCC
J 0
(-4635 3285);
DISPLAY 0.617021 (-4635 3285);
PAINT ORANGE (-4635 3285);
FORCEPROP 2 LASTPROP $XRERR UNIQUE?
J 0
(-4875 3285);
DISPLAY 0.638298 (-4875 3285);
PAINT MONO (-4875 3285);
DISPLAY INVISIBLE (-4875 3285);
WIRE 16 -1 (-5650 3275)(-5650 3825);
WIRE 16 -1 (-5650 3825)(-5525 3825);
WIRE 16 -1 (-5525 3825)(-5525 3925);
WIRE 16 -1 (-5525 3700)(-5525 3825);
WIRE 16 -1 (-8000 2725)(-8000 2575);
WIRE 16 -1 (-4000 2575)(-8000 2575);
FORCEPROP 0 LAST SIG_NAME FM_P12V_HSC_ADR1
J 0
(-4460 2585);
DISPLAY 0.617021 (-4460 2585);
PAINT ORANGE (-4460 2585);
FORCEPROP 2 LASTPROP $XRERR UNIQUE?
J 0
(-4700 2585);
DISPLAY 0.638298 (-4700 2585);
PAINT MONO (-4700 2585);
DISPLAY INVISIBLE (-4700 2585);
WIRE 16 -1 (-8000 2475)(-8000 2575);
WIRE 16 -1 (-4000 2775)(-4625 2775);
FORCEPROP 0 LAST SIG_NAME PD_HSC_RETRY_N
J 0
(-4635 2785);
DISPLAY 0.617021 (-4635 2785);
PAINT ORANGE (-4635 2785);
FORCEPROP 2 LASTPROP $XRERR UNIQUE?
J 0
(-4875 2785);
DISPLAY 0.638298 (-4875 2785);
PAINT MONO (-4875 2785);
DISPLAY INVISIBLE (-4875 2785);
WIRE 16 -1 (-4625 2775)(-4625 1125);
WIRE 16 -1 (-4000 2275)(-4575 2275);
FORCEPROP 0 LAST SIG_NAME TP_HSC_SPISSN
J 0
(-4560 2285);
DISPLAY 0.617021 (-4560 2285);
PAINT ORANGE (-4560 2285);
FORCEPROP 2 LASTPROP $XRERR UNIQUE?
J 0
(-4815 2275);
DISPLAY 0.638298 (-4815 2275);
PAINT MONO (-4815 2275);
DISPLAY INVISIBLE (-4815 2275);
WIRE 16 -1 (-4000 2525)(-7675 2525);
FORCEPROP 0 LAST SIG_NAME FM_P12V_HSC_ADR2
J 0
(-4460 2535);
DISPLAY 0.617021 (-4460 2535);
PAINT ORANGE (-4460 2535);
FORCEPROP 2 LASTPROP $XRERR UNIQUE?
J 0
(-4700 2535);
DISPLAY 0.638298 (-4700 2535);
PAINT MONO (-4700 2535);
DISPLAY INVISIBLE (-4700 2535);
WIRE 16 -1 (-7675 2525)(-7675 2750);
WIRE 16 -1 (-7675 2475)(-7675 2525);
WIRE 16 -1 (-5500 2675)(-4000 2675);
FORCEPROP 0 LAST SIG_NAME SMB_3V3SB_HSC_SDA_R
J 0
(-4610 2685);
DISPLAY 0.617021 (-4610 2685);
PAINT ORANGE (-4610 2685);
FORCEPROP 2 LASTPROP $XRERR UNIQUE?
J 0
(-4850 2685);
DISPLAY 0.638298 (-4850 2685);
PAINT MONO (-4850 2685);
DISPLAY INVISIBLE (-4850 2685);
WIRE 16 -1 (-4000 2825)(-4850 2825);
FORCEPROP 0 LAST SIG_NAME A_HSC_TIMER
J 0
(-4635 2835);
DISPLAY 0.617021 (-4635 2835);
PAINT ORANGE (-4635 2835);
WIRE 16 -1 (-4850 2825)(-5750 2825);
WIRE 16 -1 (-4850 2825)(-4850 1600);
WIRE 16 -1 (-4000 2725)(-5500 2725);
FORCEPROP 0 LAST SIG_NAME SMB_3V3SB_HSC_SCL_R
J 0
(-4610 2735);
DISPLAY 0.617021 (-4610 2735);
PAINT ORANGE (-4610 2735);
FORCEPROP 2 LASTPROP $XRERR UNIQUE?
J 0
(-4850 2735);
DISPLAY 0.638298 (-4850 2735);
PAINT MONO (-4850 2735);
DISPLAY INVISIBLE (-4850 2735);
WIRE 16 -1 (-4325 2375)(-4000 2375);
WIRE 16 -1 (-4325 2375)(-4325 1375);
WIRE 16 -1 (-4325 1375)(-2150 1375);
FORCEPROP 0 LAST SIG_NAME IRQ_HSC_FAULT_R_N
J 0
(-2785 1385);
DISPLAY 0.617021 (-2785 1385);
PAINT ORANGE (-2785 1385);
FORCEPROP 2 LASTPROP $XRERR UNIQUE?
J 0
(-3025 1385);
DISPLAY 0.638298 (-3025 1385);
PAINT MONO (-3025 1385);
DISPLAY INVISIBLE (-3025 1385);
WIRE 16 -1 (-5875 775)(-5875 475);
FORCEPROP 0 LAST SIG_NAME A_HSC_ISET_S2
R 1
J 0
(-5885 460);
DISPLAY 0.617021 (-5885 460);
PAINT ORANGE (-5885 460);
FORCEPROP 2 LASTPROP $XRERR UNIQUE?
J 0
(-6125 460);
DISPLAY 0.638298 (-6125 460);
PAINT MONO (-6125 460);
DISPLAY INVISIBLE (-6125 460);
WIRE 16 -1 (-7650 625)(-7575 625);
WIRE 16 -1 (-7575 625)(-7575 175);
WIRE 16 -1 (-7575 175)(-6300 175);
FORCEPROP 0 LAST SIG_NAME A_HSC_LOW_EN
J 0
(-7302 177);
DISPLAY 0.617021 (-7302 177);
PAINT ORANGE (-7302 177);
FORCEPROP 2 LASTPROP $XRERR UNIQUE?
J 0
(-7542 177);
DISPLAY 0.638298 (-7542 177);
PAINT MONO (-7542 177);
DISPLAY INVISIBLE (-7542 177);
WIRE 16 -1 (-7575 175)(-7650 175);
WIRE 16 -1 (-7650 175)(-7650 200);
WIRE 16 -1 (-6075 175)(-6300 175);
WIRE 16 -1 (-6300 50)(-6300 175);
WIRE 16 -1 (-5700 2725)(-6700 2725);
FORCEPROP 0 LAST SIG_NAME SMB_BMC_PMBUS_STBY_LVC3_SCL
J 0
(-6660 2735);
DISPLAY 0.617021 (-6660 2735);
PAINT ORANGE (-6660 2735);
WIRE 16 -1 (-5700 2675)(-6700 2675);
FORCEPROP 0 LAST SIG_NAME SMB_BMC_PMBUS_STBY_LVC3_SDA
J 0
(-6660 2685);
DISPLAY 0.617021 (-6660 2685);
PAINT ORANGE (-6660 2685);
WIRE 16 -1 (-8000 1175)(-6975 1175);
WIRE 16 -1 (-8000 1175)(-8000 1075);
WIRE 16 -1 (-8000 1275)(-8000 1175);
WIRE 16 -1 (-6975 1175)(-6975 1075);
WIRE 16 -1 (-6975 1275)(-6975 1175);
WIRE 16 -1 (-6975 1275)(-7275 1275);
WIRE 16 -1 (-7275 1075)(-6975 1075);
WIRE 16 -1 (-7275 1275)(-8000 1275);
WIRE 16 -1 (-8000 1075)(-7275 1075);
WIRE 16 -1 (-7275 1275)(-7275 1075);
WIRE 16 -1 (-6600 600)(-6600 825);
FORCEPROP 0 LAST SIG_NAME A_HSC_ISET_S
R 1
J 0
(-6610 560);
DISPLAY 0.617021 (-6610 560);
PAINT ORANGE (-6610 560);
FORCEPROP 2 LASTPROP $XRERR UNIQUE?
J 0
(-6850 560);
DISPLAY 0.638298 (-6850 560);
PAINT MONO (-6850 560);
DISPLAY INVISIBLE (-6850 560);
WIRE 16 -1 (-6800 300)(-6950 300);
FORCEPROP 0 LAST SIG_NAME A_HSC_HIGH_EN
J 0
(-7277 302);
DISPLAY 0.617021 (-7277 302);
PAINT ORANGE (-7277 302);
FORCEPROP 2 LASTPROP $XRERR UNIQUE?
J 0
(-7517 302);
DISPLAY 0.638298 (-7517 302);
PAINT MONO (-7517 302);
DISPLAY INVISIBLE (-7517 302);
WIRE 16 -1 (-6950 300)(-6950 50);
WIRE 16 -1 (-6950 300)(-7475 300);
WIRE 16 -1 (-7475 725)(-7475 300);
WIRE 16 -1 (-7475 300)(-7650 300);
WIRE 16 -1 (-7650 725)(-7475 725);
WIRE 16 -1 (-7650 675)(-7525 675);
WIRE 16 -1 (-7525 675)(-7525 250);
WIRE 16 -1 (-7525 250)(-7300 250);
FORCEPROP 0 LAST SIG_NAME A_HSC_OCP_SEL
R 1
J 0
(-7302 327);
DISPLAY 0.617021 (-7302 327);
PAINT ORANGE (-7302 327);
FORCEPROP 2 LASTPROP $XRERR UNIQUE?
J 0
(-7542 327);
DISPLAY 0.638298 (-7542 327);
PAINT MONO (-7542 327);
DISPLAY INVISIBLE (-7542 327);
WIRE 16 -1 (-7650 250)(-7525 250);
WIRE 16 -1 (-7300 250)(-7300 650);
DOT 1 (-6300 -225);
DOT 1 (-7575 175);
DOT 1 (-7525 250);
DOT 1 (-7475 300);
DOT 1 (-8000 1175);
DOT 1 (-7275 1275);
DOT 1 (-7275 1075);
DOT 1 (-6950 300);
DOT 1 (-6300 175);
DOT 1 (-6975 1175);
DOT 1 (-6725 1875);
DOT 1 (-6600 1150);
DOT 1 (-6600 1100);
DOT 1 (-6150 1100);
DOT 1 (-8000 2575);
DOT 1 (-7825 2975);
DOT 1 (-7675 2525);
DOT 1 (-7675 2225);
DOT 1 (-7200 3325);
DOT 1 (-7200 3800);
DOT 1 (-6725 2325);
DOT 1 (-6775 3800);
DOT 1 (-6375 3350);
DOT 1 (-6500 3800);
DOT 1 (-5400 575);
DOT 1 (-5600 975);
DOT 1 (-5300 1050);
DOT 1 (-5600 1700);
DOT 1 (-5300 1700);
DOT 1 (-4725 750);
DOT 1 (-5000 1050);
DOT 1 (-6075 3800);
DOT 1 (-5525 3825);
DOT 1 (-5100 2150);
DOT 1 (-4850 2825);
DOT 1 (-5100 3175);
DOT 1 (-6675 4225);
DOT 1 (-6500 4225);
DOT 1 (-5525 4225);
DOT 1 (-3125 925);
DOT 1 (-2825 925);
DOT 1 (-1825 1650);
DOT 1 (-400 2825);
FORCENOTE
ROOM: HOT_SWAP
(-7925 -225) 0;
DISPLAY LEFT (-7925 -225);
DISPLAY 1.595745 (-7925 -225);
PAINT PURPLE (-7925 -225);
FORCENOTE
OCP OPTION
(-7775 1300) 0;
DISPLAY LEFT (-7775 1300);
DISPLAY 1.276596 (-7775 1300);
PAINT PURPLE (-7775 1300);
FORCENOTE
PIN 2-3 
(-7975 1100) 0;
DISPLAY LEFT (-7975 1100);
DISPLAY 1.276596 (-7975 1100);
PAINT PURPLE (-7975 1100);
FORCENOTE
0X22 (8 BIT)
(-8050 1775) 0;
DISPLAY LEFT (-8050 1775);
DISPLAY 1.021277 (-8050 1775);
PAINT PURPLE (-8050 1775);
FORCENOTE
0X11 (7 BIT)
(-8050 1850) 0;
DISPLAY LEFT (-8050 1850);
DISPLAY 1.021277 (-8050 1850);
PAINT PURPLE (-8050 1850);
FORCENOTE
PMBUS ADDRESS :
(-8050 1925) 0;
DISPLAY LEFT (-8050 1925);
DISPLAY 1.021277 (-8050 1925);
PAINT PURPLE (-8050 1925);
FORCENOTE
PIN 1-2 (DEFAULT)
(-7975 1200) 0;
DISPLAY LEFT (-7975 1200);
DISPLAY 1.276596 (-7975 1200);
PAINT PURPLE (-7975 1200);
FORCENOTE
41.4A
(-7225 1100) 0;
DISPLAY LEFT (-7225 1100);
DISPLAY 1.276596 (-7225 1100);
PAINT PURPLE (-7225 1100);
FORCENOTE
48.8A
(-7225 1200) 0;
DISPLAY LEFT (-7225 1200);
DISPLAY 1.276596 (-7225 1200);
PAINT PURPLE (-7225 1200);
FORCENOTE
THRESHOLD 9.26V
(-6675 2200) 0;
DISPLAY LEFT (-6675 2200);
DISPLAY 1.021277 (-6675 2200);
PAINT PURPLE (-6675 2200);
FORCENOTE
PSET: 78W
(-6050 1575) 0;
DISPLAY LEFT (-6050 1575);
DISPLAY 1.021277 (-6050 1575);
PAINT PURPLE (-6050 1575);
FORCENOTE
ISTART: 9.92A
(-5525 1725) 0;
DISPLAY LEFT (-5525 1725);
DISPLAY 1.021277 (-5525 1725);
PAINT PURPLE (-5525 1725);
FORCENOTE
TIMER: 620US
(-4900 1650) 0;
DISPLAY LEFT (-4900 1650);
DISPLAY 1.021277 (-4900 1650);
PAINT PURPLE (-4900 1650);
FORCENOTE
UV: P12V_PSU <=10.091V
(-6550 4250) 0;
DISPLAY LEFT (-6550 4250);
DISPLAY 1.021277 (-6550 4250);
PAINT PURPLE (-6550 4250);
FORCENOTE
OV: P12V_PSU >=14.333V
(-6550 4325) 0;
DISPLAY LEFT (-6550 4325);
DISPLAY 1.021277 (-6550 4325);
PAINT PURPLE (-6550 4325);
FORCENOTE
STUFF = RETRY MODE
(-4625 550) 0;
DISPLAY LEFT (-4625 550);
DISPLAY 1.021277 (-4625 550);
PAINT PURPLE (-4625 550);
FORCENOTE
EMPTY = LATCH-OFF MODE (DEFAULT)
(-4625 600) 0;
DISPLAY LEFT (-4625 600);
DISPLAY 1.021277 (-4625 600);
PAINT PURPLE (-4625 600);
QUIT
